G04*
G04 #@! TF.GenerationSoftware,Altium Limited,Altium Designer,23.7.1 (13)*
G04*
G04 Layer_Physical_Order=5*
G04 Layer_Color=1930808*
%FSLAX25Y25*%
%MOIN*%
G70*
G04*
G04 #@! TF.SameCoordinates,AF00DCEB-AC48-4C7C-91EA-99F42E284231*
G04*
G04*
G04 #@! TF.FilePolarity,Positive*
G04*
G01*
G75*
%ADD211R,0.10827X0.10827*%
%ADD212C,0.10827*%
%ADD217C,0.06299*%
%ADD236C,0.06102*%
%ADD240O,0.04921X0.04134*%
%ADD241O,0.07480X0.04724*%
%ADD242C,0.25591*%
%ADD244C,0.10000*%
%ADD246C,0.08661*%
%ADD249C,0.05906*%
%ADD250C,0.01600*%
G36*
X34788Y20107D02*
X35055Y19607D01*
X34919Y19403D01*
X34779Y18701D01*
X34919Y17999D01*
X35155Y17644D01*
X34949Y17093D01*
X34731Y17050D01*
X34135Y16652D01*
X33737Y16057D01*
X33598Y15354D01*
X33737Y14652D01*
X34135Y14057D01*
X34731Y13659D01*
X35237Y13558D01*
X35342Y13351D01*
X35423Y13046D01*
X35067Y12513D01*
X34927Y11811D01*
X35067Y11109D01*
X35465Y10513D01*
X35523Y10474D01*
X35521Y10229D01*
X35453Y9920D01*
X34923Y9565D01*
X34525Y8970D01*
X34385Y8268D01*
X34525Y7565D01*
X34923Y6970D01*
X35232Y6764D01*
X35316Y6224D01*
X35285Y6172D01*
X34919Y5624D01*
X34779Y4921D01*
X34919Y4219D01*
X35201Y3796D01*
X35138Y3361D01*
X35036Y3211D01*
X34529Y2873D01*
X34131Y2277D01*
X33992Y1575D01*
X34131Y872D01*
X34529Y277D01*
X35124Y-121D01*
X35213Y-138D01*
X35319Y-669D01*
X35316Y-671D01*
X34919Y-1266D01*
X34779Y-1969D01*
X34919Y-2671D01*
X35316Y-3266D01*
X35912Y-3664D01*
X36614Y-3804D01*
X37317Y-3664D01*
X37912Y-3266D01*
X38310Y-2671D01*
X38449Y-1969D01*
X38310Y-1266D01*
X37912Y-671D01*
X37317Y-273D01*
X37228Y-255D01*
X37122Y276D01*
X37124Y277D01*
X37522Y872D01*
X37662Y1575D01*
X37522Y2277D01*
X37239Y2701D01*
X37303Y3135D01*
X37405Y3285D01*
X37912Y3624D01*
X38310Y4219D01*
X38449Y4921D01*
X38310Y5624D01*
X37912Y6219D01*
X37603Y6425D01*
X37519Y6965D01*
X37549Y7017D01*
X37916Y7565D01*
X38056Y8268D01*
X37916Y8970D01*
X37518Y9565D01*
X37459Y9605D01*
X37462Y9850D01*
X37530Y10159D01*
X38060Y10513D01*
X38458Y11109D01*
X38597Y11811D01*
X38458Y12513D01*
X38060Y13109D01*
X37464Y13507D01*
X36958Y13607D01*
X36854Y13814D01*
X36773Y14119D01*
X37129Y14652D01*
X37268Y15354D01*
X37129Y16057D01*
X36892Y16411D01*
X37099Y16962D01*
X37317Y17005D01*
X37912Y17403D01*
X38310Y17999D01*
X38449Y18701D01*
X38310Y19403D01*
X38173Y19607D01*
X38441Y20107D01*
X77589D01*
X77741Y19607D01*
X77442Y19408D01*
X77045Y18813D01*
X76905Y18110D01*
X77045Y17408D01*
X77442Y16813D01*
Y16652D01*
X77045Y16057D01*
X76905Y15354D01*
X77045Y14652D01*
X77442Y14057D01*
X78038Y13659D01*
X78740Y13519D01*
X79443Y13659D01*
X80038Y14057D01*
X80436Y14652D01*
X80575Y15354D01*
X80436Y16057D01*
X80038Y16652D01*
Y16813D01*
X80436Y17408D01*
X80575Y18110D01*
X80436Y18813D01*
X80038Y19408D01*
X79740Y19607D01*
X79892Y20107D01*
X150030D01*
X150181Y19607D01*
X149883Y19408D01*
X149486Y18813D01*
X149346Y18110D01*
X149486Y17408D01*
X149883Y16813D01*
X150479Y16415D01*
X150569Y16397D01*
Y15887D01*
X150479Y15869D01*
X149883Y15471D01*
X149486Y14876D01*
X149346Y14173D01*
X149486Y13471D01*
X149883Y12876D01*
X150479Y12478D01*
X150639Y12446D01*
X150745Y11915D01*
X150484Y11741D01*
X150086Y11145D01*
X149946Y10443D01*
X150086Y9741D01*
X150484Y9145D01*
X151079Y8748D01*
X151782Y8608D01*
X152484Y8748D01*
X153079Y9145D01*
X153477Y9741D01*
X153617Y10443D01*
X153477Y11145D01*
X153079Y11741D01*
X152484Y12139D01*
X152324Y12171D01*
X152218Y12701D01*
X152479Y12876D01*
X152877Y13471D01*
X153016Y14173D01*
X152877Y14876D01*
X152479Y15471D01*
X151883Y15869D01*
X151793Y15887D01*
Y16397D01*
X151883Y16415D01*
X152479Y16813D01*
X152877Y17408D01*
X153016Y18110D01*
X152877Y18813D01*
X152479Y19408D01*
X152181Y19607D01*
X152332Y20107D01*
X629735Y20107D01*
X629735Y-364265D01*
X629294Y-364693D01*
X282449Y-364693D01*
Y-392667D01*
X200449D01*
Y-384193D01*
X197249Y-380993D01*
X194449D01*
X191249Y-384193D01*
Y-392667D01*
X149149D01*
Y-368693D01*
X144549Y-364093D01*
X137349D01*
X132849Y-368593D01*
Y-382888D01*
X103149D01*
Y-364393D01*
X29149D01*
Y-396793D01*
X-28251D01*
Y19731D01*
X-27875Y20107D01*
X34788D01*
D02*
G37*
%LPC*%
G36*
X20079Y19158D02*
X19376Y19018D01*
X18781Y18621D01*
X18383Y18025D01*
X18244Y17323D01*
X18383Y16621D01*
X18781Y16025D01*
X19376Y15627D01*
X20079Y15488D01*
X20781Y15627D01*
X21376Y16025D01*
X21774Y16621D01*
X21914Y17323D01*
X21774Y18025D01*
X21376Y18621D01*
X20781Y19018D01*
X20079Y19158D01*
D02*
G37*
G36*
X142520Y15024D02*
X141817Y14885D01*
X141222Y14487D01*
X140824Y13891D01*
X140684Y13189D01*
X140824Y12487D01*
X141222Y11891D01*
X141817Y11493D01*
X142520Y11354D01*
X143222Y11493D01*
X143817Y11891D01*
X144215Y12487D01*
X144355Y13189D01*
X144215Y13891D01*
X143817Y14487D01*
X143222Y14885D01*
X142520Y15024D01*
D02*
G37*
G36*
X20079Y12465D02*
X19376Y12325D01*
X18781Y11928D01*
X18383Y11332D01*
X18244Y10630D01*
X18383Y9928D01*
X18781Y9332D01*
X19376Y8934D01*
X20079Y8795D01*
X20781Y8934D01*
X21376Y9332D01*
X21774Y9928D01*
X21914Y10630D01*
X21774Y11332D01*
X21376Y11928D01*
X20781Y12325D01*
X20079Y12465D01*
D02*
G37*
G36*
X169291Y15221D02*
X168589Y15081D01*
X167994Y14683D01*
X167596Y14088D01*
X167456Y13386D01*
X167596Y12684D01*
X167994Y12088D01*
X168435Y11794D01*
X168448Y11753D01*
Y11279D01*
X168435Y11238D01*
X167994Y10943D01*
X167596Y10348D01*
X167456Y9646D01*
X167596Y8943D01*
X167994Y8348D01*
X168589Y7950D01*
X169291Y7810D01*
X169994Y7950D01*
X170589Y8348D01*
X170987Y8943D01*
X171127Y9646D01*
X170987Y10348D01*
X170589Y10943D01*
X170148Y11238D01*
X170134Y11279D01*
Y11753D01*
X170148Y11794D01*
X170589Y12088D01*
X170987Y12684D01*
X171127Y13386D01*
X170987Y14088D01*
X170589Y14683D01*
X169994Y15081D01*
X169291Y15221D01*
D02*
G37*
G36*
X159843Y11481D02*
X159140Y11341D01*
X158545Y10943D01*
X158147Y10348D01*
X158007Y9646D01*
X158147Y8943D01*
X158545Y8348D01*
X159140Y7950D01*
X159843Y7810D01*
X160545Y7950D01*
X161140Y8348D01*
X161538Y8943D01*
X161678Y9646D01*
X161538Y10348D01*
X161140Y10943D01*
X160545Y11341D01*
X159843Y11481D01*
D02*
G37*
G36*
X110589Y3424D02*
X109887Y3284D01*
X109291Y2886D01*
X108893Y2291D01*
X108858Y2112D01*
X108268Y2229D01*
X107565Y2089D01*
X106970Y1691D01*
X106572Y1096D01*
X106432Y394D01*
X106572Y-309D01*
X106970Y-904D01*
X107565Y-1302D01*
X108268Y-1442D01*
X108970Y-1302D01*
X109565Y-904D01*
X109963Y-309D01*
X109999Y-129D01*
X110589Y-246D01*
X110879Y-189D01*
X110903Y-309D01*
X111301Y-904D01*
X111896Y-1302D01*
X112598Y-1442D01*
X113301Y-1302D01*
X113896Y-904D01*
X114294Y-309D01*
X114434Y394D01*
X114294Y1096D01*
X113896Y1691D01*
X113301Y2089D01*
X112598Y2229D01*
X112308Y2171D01*
X112285Y2291D01*
X111887Y2886D01*
X111291Y3284D01*
X110589Y3424D01*
D02*
G37*
G36*
X20079Y5772D02*
X19376Y5633D01*
X18781Y5235D01*
X18383Y4639D01*
X18244Y3937D01*
X18383Y3235D01*
X18781Y2639D01*
X19376Y2241D01*
X20079Y2102D01*
X20781Y2241D01*
X21376Y2639D01*
X21774Y3235D01*
X21914Y3937D01*
X21774Y4639D01*
X21376Y5235D01*
X20781Y5633D01*
X20079Y5772D01*
D02*
G37*
G36*
X78740Y11678D02*
X78038Y11538D01*
X77442Y11140D01*
X77045Y10545D01*
X76905Y9843D01*
X77045Y9140D01*
X77442Y8545D01*
X77483Y8518D01*
Y8018D01*
X77442Y7991D01*
X77045Y7395D01*
X76905Y6693D01*
X77045Y5991D01*
X77421Y5428D01*
X77483Y5281D01*
Y4955D01*
X77421Y4808D01*
X77045Y4246D01*
X76905Y3543D01*
X77045Y2841D01*
X77442Y2246D01*
X78038Y1848D01*
X78740Y1708D01*
X79443Y1848D01*
X80038Y2246D01*
X80436Y2841D01*
X80575Y3543D01*
X80436Y4246D01*
X80060Y4808D01*
X79997Y4955D01*
Y5281D01*
X80060Y5428D01*
X80436Y5991D01*
X80575Y6693D01*
X80436Y7395D01*
X80038Y7991D01*
X79997Y8018D01*
Y8518D01*
X80038Y8545D01*
X80436Y9140D01*
X80575Y9843D01*
X80436Y10545D01*
X80038Y11140D01*
X79443Y11538D01*
X78740Y11678D01*
D02*
G37*
G36*
X552709Y13889D02*
X551452Y13766D01*
X550243Y13399D01*
X549129Y12803D01*
X548153Y12002D01*
X547351Y11025D01*
X546756Y9911D01*
X546389Y8702D01*
X546265Y7445D01*
X546389Y6188D01*
X546756Y4979D01*
X547351Y3865D01*
X548153Y2888D01*
X549129Y2087D01*
X550243Y1491D01*
X551452Y1124D01*
X552709Y1001D01*
X553967Y1124D01*
X555176Y1491D01*
X556290Y2087D01*
X557266Y2888D01*
X558068Y3865D01*
X558663Y4979D01*
X559030Y6188D01*
X559154Y7445D01*
X559030Y8702D01*
X558663Y9911D01*
X558068Y11025D01*
X557266Y12002D01*
X556290Y12803D01*
X555176Y13399D01*
X553967Y13766D01*
X552709Y13889D01*
D02*
G37*
G36*
X56693Y2895D02*
X55991Y2755D01*
X55395Y2357D01*
X54997Y1762D01*
X54858Y1060D01*
X54997Y357D01*
X55395Y-238D01*
X55991Y-636D01*
X56693Y-776D01*
X57395Y-636D01*
X57991Y-238D01*
X58389Y357D01*
X58528Y1060D01*
X58389Y1762D01*
X57991Y2357D01*
X57395Y2755D01*
X56693Y2895D01*
D02*
G37*
G36*
X61811Y2623D02*
X61109Y2483D01*
X60513Y2085D01*
X60115Y1490D01*
X59976Y787D01*
X60115Y85D01*
X60513Y-510D01*
X61109Y-908D01*
X61811Y-1048D01*
X62513Y-908D01*
X63109Y-510D01*
X63507Y85D01*
X63646Y787D01*
X63507Y1490D01*
X63109Y2085D01*
X62513Y2483D01*
X61811Y2623D01*
D02*
G37*
G36*
X141339Y2229D02*
X140636Y2089D01*
X140041Y1691D01*
X139643Y1096D01*
X139503Y394D01*
X139643Y-309D01*
X140041Y-904D01*
X140636Y-1302D01*
X141339Y-1442D01*
X142041Y-1302D01*
X142636Y-904D01*
X143034Y-309D01*
X143174Y394D01*
X143034Y1096D01*
X142636Y1691D01*
X142041Y2089D01*
X141339Y2229D01*
D02*
G37*
G36*
X365581Y18839D02*
X363855Y18704D01*
X362171Y18299D01*
X360571Y17637D01*
X359095Y16732D01*
X357779Y15608D01*
X356654Y14291D01*
X355749Y12815D01*
X355087Y11215D01*
X354683Y9532D01*
X354547Y7806D01*
X354683Y6079D01*
X355087Y4396D01*
X355749Y2796D01*
X356654Y1320D01*
X357779Y3D01*
X359095Y-1121D01*
X360571Y-2026D01*
X362171Y-2688D01*
X363855Y-3093D01*
X365581Y-3229D01*
X367307Y-3093D01*
X368990Y-2688D01*
X370590Y-2026D01*
X372066Y-1121D01*
X373383Y3D01*
X374507Y1320D01*
X375412Y2796D01*
X376075Y4396D01*
X376479Y6079D01*
X376615Y7806D01*
X376479Y9532D01*
X376075Y11215D01*
X375412Y12815D01*
X374507Y14291D01*
X373383Y15608D01*
X372066Y16732D01*
X370590Y17637D01*
X368990Y18299D01*
X367307Y18704D01*
X365581Y18839D01*
D02*
G37*
G36*
X127392D02*
X125666Y18704D01*
X123982Y18299D01*
X122382Y17637D01*
X120906Y16732D01*
X119589Y15608D01*
X118465Y14291D01*
X117560Y12815D01*
X116898Y11215D01*
X116494Y9532D01*
X116358Y7806D01*
X116494Y6079D01*
X116898Y4396D01*
X117560Y2796D01*
X118465Y1320D01*
X119589Y3D01*
X120906Y-1121D01*
X122382Y-2026D01*
X123982Y-2688D01*
X125666Y-3093D01*
X127392Y-3229D01*
X129118Y-3093D01*
X130801Y-2688D01*
X132401Y-2026D01*
X133877Y-1121D01*
X135194Y3D01*
X136319Y1320D01*
X137223Y2796D01*
X137886Y4396D01*
X138290Y6079D01*
X138426Y7806D01*
X138290Y9532D01*
X137886Y11215D01*
X137223Y12815D01*
X136319Y14291D01*
X135194Y15608D01*
X133877Y16732D01*
X132401Y17637D01*
X130801Y18299D01*
X129118Y18704D01*
X127392Y18839D01*
D02*
G37*
G36*
X162598Y261D02*
X161896Y121D01*
X161301Y-277D01*
X160903Y-872D01*
X160763Y-1575D01*
X160903Y-2277D01*
X161301Y-2873D01*
X161896Y-3270D01*
X162598Y-3410D01*
X163301Y-3270D01*
X163896Y-2873D01*
X164294Y-2277D01*
X164434Y-1575D01*
X164294Y-872D01*
X163896Y-277D01*
X163301Y121D01*
X162598Y261D01*
D02*
G37*
G36*
X194882Y4579D02*
X193799Y4436D01*
X192789Y4018D01*
X191922Y3353D01*
X191257Y2486D01*
X190839Y1477D01*
X190697Y394D01*
X190839Y-690D01*
X191257Y-1699D01*
X191922Y-2566D01*
X192789Y-3231D01*
X193799Y-3649D01*
X194882Y-3792D01*
X195965Y-3649D01*
X196975Y-3231D01*
X197841Y-2566D01*
X198507Y-1699D01*
X198925Y-690D01*
X199067Y394D01*
X198925Y1477D01*
X198507Y2486D01*
X197841Y3353D01*
X196975Y4018D01*
X195965Y4436D01*
X194882Y4579D01*
D02*
G37*
G36*
X19685Y-527D02*
X18983Y-667D01*
X18387Y-1065D01*
X17989Y-1660D01*
X17850Y-2362D01*
X17989Y-3064D01*
X18387Y-3660D01*
X18983Y-4058D01*
X19685Y-4197D01*
X20387Y-4058D01*
X20983Y-3660D01*
X21381Y-3064D01*
X21520Y-2362D01*
X21381Y-1660D01*
X20983Y-1065D01*
X20387Y-667D01*
X19685Y-527D01*
D02*
G37*
G36*
X137598Y-4464D02*
X136896Y-4604D01*
X136301Y-5001D01*
X136127Y-5261D01*
X135526D01*
X135353Y-5001D01*
X134757Y-4604D01*
X134055Y-4464D01*
X133353Y-4604D01*
X132757Y-5001D01*
X132360Y-5597D01*
X132220Y-6299D01*
X132360Y-7001D01*
X132757Y-7597D01*
X133353Y-7995D01*
X134055Y-8134D01*
X134757Y-7995D01*
X135353Y-7597D01*
X135526Y-7338D01*
X136127D01*
X136301Y-7597D01*
X136896Y-7995D01*
X137598Y-8134D01*
X138301Y-7995D01*
X138896Y-7597D01*
X139294Y-7001D01*
X139434Y-6299D01*
X139294Y-5597D01*
X138896Y-5001D01*
X138301Y-4604D01*
X137598Y-4464D01*
D02*
G37*
G36*
X603110Y6128D02*
X601757Y5995D01*
X600456Y5601D01*
X599258Y4960D01*
X598207Y4098D01*
X597344Y3047D01*
X596704Y1848D01*
X596309Y548D01*
X596176Y-805D01*
X596309Y-2158D01*
X596704Y-3458D01*
X597344Y-4657D01*
X598207Y-5708D01*
X599258Y-6570D01*
X600456Y-7211D01*
X601757Y-7605D01*
X603110Y-7739D01*
X604462Y-7605D01*
X605763Y-7211D01*
X606961Y-6570D01*
X608012Y-5708D01*
X608874Y-4657D01*
X609515Y-3458D01*
X609910Y-2158D01*
X610043Y-805D01*
X609910Y548D01*
X609515Y1848D01*
X608874Y3047D01*
X608012Y4098D01*
X606961Y4960D01*
X605763Y5601D01*
X604462Y5995D01*
X603110Y6128D01*
D02*
G37*
G36*
X209449Y-1708D02*
X208747Y-1848D01*
X208151Y-2246D01*
X207753Y-2841D01*
X207614Y-3543D01*
X207749Y-4226D01*
X207360Y-4809D01*
X207220Y-5512D01*
X207360Y-6214D01*
X207548Y-6496D01*
X207360Y-6778D01*
X207220Y-7480D01*
X207360Y-8183D01*
X207757Y-8778D01*
X208353Y-9176D01*
X209055Y-9316D01*
X209757Y-9176D01*
X210353Y-8778D01*
X210751Y-8183D01*
X210890Y-7480D01*
X210751Y-6778D01*
X210562Y-6496D01*
X210751Y-6214D01*
X210890Y-5512D01*
X210755Y-4829D01*
X211144Y-4246D01*
X211284Y-3543D01*
X211144Y-2841D01*
X210747Y-2246D01*
X210151Y-1848D01*
X209449Y-1708D01*
D02*
G37*
G36*
X35731Y-8007D02*
X35029Y-8147D01*
X34434Y-8545D01*
X34036Y-9140D01*
X33896Y-9843D01*
X34036Y-10545D01*
X34434Y-11140D01*
X35029Y-11538D01*
X35731Y-11678D01*
X36434Y-11538D01*
X37029Y-11140D01*
X37427Y-10545D01*
X37567Y-9843D01*
X37427Y-9140D01*
X37029Y-8545D01*
X36434Y-8147D01*
X35731Y-8007D01*
D02*
G37*
G36*
X107832Y-8362D02*
X107130Y-8501D01*
X106535Y-8899D01*
X106137Y-9494D01*
X105997Y-10197D01*
X106137Y-10899D01*
X106535Y-11495D01*
X107130Y-11892D01*
X107832Y-12032D01*
X108535Y-11892D01*
X109130Y-11495D01*
X109528Y-10899D01*
X109668Y-10197D01*
X109528Y-9494D01*
X109130Y-8899D01*
X108535Y-8501D01*
X107832Y-8362D01*
D02*
G37*
G36*
X153543Y-8598D02*
X152841Y-8738D01*
X152246Y-9135D01*
X151848Y-9731D01*
X151708Y-10433D01*
X151848Y-11135D01*
X152246Y-11731D01*
X152841Y-12129D01*
X153543Y-12268D01*
X154246Y-12129D01*
X154841Y-11731D01*
X155239Y-11135D01*
X155379Y-10433D01*
X155239Y-9731D01*
X154841Y-9135D01*
X154246Y-8738D01*
X153543Y-8598D01*
D02*
G37*
G36*
X168110Y-8795D02*
X167408Y-8934D01*
X166813Y-9332D01*
X166415Y-9928D01*
X166275Y-10630D01*
X166415Y-11332D01*
X166813Y-11928D01*
X167408Y-12325D01*
X168110Y-12465D01*
X168813Y-12325D01*
X169408Y-11928D01*
X169806Y-11332D01*
X169946Y-10630D01*
X169806Y-9928D01*
X169408Y-9332D01*
X168813Y-8934D01*
X168110Y-8795D01*
D02*
G37*
G36*
X214567Y-9582D02*
X213865Y-9722D01*
X213269Y-10120D01*
X212871Y-10715D01*
X212732Y-11417D01*
X212871Y-12120D01*
X213269Y-12715D01*
X213865Y-13113D01*
X214567Y-13253D01*
X215269Y-13113D01*
X215865Y-12715D01*
X216263Y-12120D01*
X216402Y-11417D01*
X216263Y-10715D01*
X215865Y-10120D01*
X215269Y-9722D01*
X214567Y-9582D01*
D02*
G37*
G36*
X0Y13542D02*
X-2118Y13375D01*
X-4185Y12879D01*
X-6148Y12066D01*
X-7960Y10955D01*
X-9576Y9576D01*
X-10955Y7960D01*
X-12066Y6148D01*
X-12879Y4185D01*
X-13375Y2118D01*
X-13542Y0D01*
X-13375Y-2118D01*
X-12879Y-4185D01*
X-12066Y-6148D01*
X-10955Y-7960D01*
X-9576Y-9576D01*
X-7960Y-10955D01*
X-6148Y-12066D01*
X-4185Y-12879D01*
X-2118Y-13375D01*
X0Y-13542D01*
X2118Y-13375D01*
X4185Y-12879D01*
X6148Y-12066D01*
X7960Y-10955D01*
X9576Y-9576D01*
X10955Y-7960D01*
X12066Y-6148D01*
X12879Y-4185D01*
X13375Y-2118D01*
X13542Y0D01*
X13375Y2118D01*
X12879Y4185D01*
X12066Y6148D01*
X10955Y7960D01*
X9576Y9576D01*
X7960Y10955D01*
X6148Y12066D01*
X4185Y12879D01*
X2118Y13375D01*
X0Y13542D01*
D02*
G37*
G36*
X144685Y-9976D02*
X143983Y-10115D01*
X143387Y-10513D01*
X142990Y-11109D01*
X142850Y-11811D01*
X142990Y-12513D01*
X143387Y-13109D01*
X143983Y-13507D01*
X144685Y-13646D01*
X145387Y-13507D01*
X145983Y-13109D01*
X146381Y-12513D01*
X146520Y-11811D01*
X146381Y-11109D01*
X145983Y-10513D01*
X145387Y-10115D01*
X144685Y-9976D01*
D02*
G37*
G36*
X127165Y-10763D02*
X126463Y-10903D01*
X125868Y-11301D01*
X125470Y-11896D01*
X125330Y-12598D01*
X125470Y-13301D01*
X125868Y-13896D01*
X126463Y-14294D01*
X127165Y-14434D01*
X127868Y-14294D01*
X128463Y-13896D01*
X128861Y-13301D01*
X129001Y-12598D01*
X128861Y-11896D01*
X128463Y-11301D01*
X127868Y-10903D01*
X127165Y-10763D01*
D02*
G37*
G36*
X162598Y-7614D02*
X161896Y-7753D01*
X161301Y-8151D01*
X160903Y-8747D01*
X160763Y-9449D01*
X160903Y-10151D01*
X161301Y-10746D01*
X161742Y-11041D01*
X161756Y-11082D01*
Y-11556D01*
X161742Y-11597D01*
X161301Y-11891D01*
X160903Y-12487D01*
X160763Y-13189D01*
X160903Y-13891D01*
X161301Y-14487D01*
X161896Y-14885D01*
X162598Y-15024D01*
X163301Y-14885D01*
X163896Y-14487D01*
X164294Y-13891D01*
X164434Y-13189D01*
X164294Y-12487D01*
X163896Y-11891D01*
X163455Y-11597D01*
X163441Y-11556D01*
Y-11082D01*
X163455Y-11041D01*
X163896Y-10746D01*
X164294Y-10151D01*
X164434Y-9449D01*
X164294Y-8747D01*
X163896Y-8151D01*
X163301Y-7753D01*
X162598Y-7614D01*
D02*
G37*
G36*
X552709Y-2611D02*
X551452Y-2734D01*
X550243Y-3101D01*
X549129Y-3697D01*
X548153Y-4498D01*
X547351Y-5475D01*
X546756Y-6589D01*
X546389Y-7798D01*
X546265Y-9055D01*
X546389Y-10312D01*
X546756Y-11521D01*
X547351Y-12635D01*
X548153Y-13612D01*
X549129Y-14413D01*
X550243Y-15009D01*
X551452Y-15376D01*
X552709Y-15499D01*
X553967Y-15376D01*
X555176Y-15009D01*
X556290Y-14413D01*
X557266Y-13612D01*
X558068Y-12635D01*
X558663Y-11521D01*
X559030Y-10312D01*
X559154Y-9055D01*
X559030Y-7798D01*
X558663Y-6589D01*
X558068Y-5475D01*
X557266Y-4498D01*
X556290Y-3697D01*
X555176Y-3101D01*
X553967Y-2734D01*
X552709Y-2611D01*
D02*
G37*
G36*
X211811Y-14700D02*
X211109Y-14840D01*
X210513Y-15238D01*
X210116Y-15833D01*
X209976Y-16535D01*
X210116Y-17238D01*
X210513Y-17833D01*
X211109Y-18231D01*
X211811Y-18371D01*
X212513Y-18231D01*
X213109Y-17833D01*
X213507Y-17238D01*
X213646Y-16535D01*
X213507Y-15833D01*
X213109Y-15238D01*
X212513Y-14840D01*
X211811Y-14700D01*
D02*
G37*
G36*
X118898Y-15094D02*
X118195Y-15234D01*
X117600Y-15631D01*
X117202Y-16227D01*
X117062Y-16929D01*
X117202Y-17631D01*
X117600Y-18227D01*
X118195Y-18625D01*
X118898Y-18764D01*
X119600Y-18625D01*
X120195Y-18227D01*
X120593Y-17631D01*
X120733Y-16929D01*
X120593Y-16227D01*
X120195Y-15631D01*
X119600Y-15234D01*
X118898Y-15094D01*
D02*
G37*
G36*
X85853Y-11944D02*
X85151Y-12084D01*
X84556Y-12482D01*
X84158Y-13077D01*
X84018Y-13780D01*
X84158Y-14482D01*
X84556Y-15077D01*
X84583Y-15096D01*
Y-15596D01*
X84529Y-15631D01*
X84131Y-16227D01*
X83991Y-16929D01*
X84131Y-17631D01*
X84529Y-18227D01*
X85124Y-18625D01*
X85827Y-18764D01*
X86529Y-18625D01*
X87125Y-18227D01*
X87522Y-17631D01*
X87662Y-16929D01*
X87522Y-16227D01*
X87125Y-15631D01*
X87097Y-15613D01*
Y-15113D01*
X87151Y-15077D01*
X87549Y-14482D01*
X87688Y-13780D01*
X87549Y-13077D01*
X87151Y-12482D01*
X86556Y-12084D01*
X85853Y-11944D01*
D02*
G37*
G36*
X35731Y-17062D02*
X35029Y-17202D01*
X34434Y-17600D01*
X34036Y-18195D01*
X33896Y-18898D01*
X34036Y-19600D01*
X34434Y-20195D01*
X35029Y-20593D01*
X35731Y-20733D01*
X36434Y-20593D01*
X37029Y-20195D01*
X37427Y-19600D01*
X37567Y-18898D01*
X37427Y-18195D01*
X37029Y-17600D01*
X36434Y-17202D01*
X35731Y-17062D01*
D02*
G37*
G36*
X500787Y-18244D02*
X500085Y-18383D01*
X499490Y-18781D01*
X499092Y-19376D01*
X498952Y-20079D01*
X499092Y-20781D01*
X499490Y-21376D01*
X500085Y-21774D01*
X500787Y-21914D01*
X501490Y-21774D01*
X502085Y-21376D01*
X502483Y-20781D01*
X502623Y-20079D01*
X502483Y-19376D01*
X502085Y-18781D01*
X501490Y-18383D01*
X500787Y-18244D01*
D02*
G37*
G36*
X601181Y-21787D02*
X600479Y-21926D01*
X599883Y-22324D01*
X599485Y-22920D01*
X599468Y-23010D01*
X598958D01*
X598940Y-22920D01*
X598542Y-22324D01*
X597946Y-21926D01*
X597244Y-21787D01*
X596542Y-21926D01*
X595946Y-22324D01*
X595548Y-22920D01*
X595409Y-23622D01*
X595548Y-24324D01*
X595925Y-24887D01*
X595987Y-25034D01*
Y-25360D01*
X595925Y-25507D01*
X595548Y-26069D01*
X595409Y-26772D01*
X595548Y-27474D01*
X595946Y-28069D01*
X595987Y-28096D01*
Y-28596D01*
X595946Y-28624D01*
X595548Y-29219D01*
X595409Y-29921D01*
X595548Y-30624D01*
X595946Y-31219D01*
X596542Y-31617D01*
X597244Y-31756D01*
X597946Y-31617D01*
X598542Y-31219D01*
X598940Y-30624D01*
X598958Y-30533D01*
X599468D01*
X599485Y-30624D01*
X599883Y-31219D01*
X600479Y-31617D01*
X601181Y-31756D01*
X601883Y-31617D01*
X602479Y-31219D01*
X602877Y-30624D01*
X603016Y-29921D01*
X602877Y-29219D01*
X602479Y-28624D01*
X602438Y-28596D01*
Y-28096D01*
X602479Y-28069D01*
X602877Y-27474D01*
X603016Y-26772D01*
X602877Y-26069D01*
X602501Y-25507D01*
X602438Y-25360D01*
Y-25034D01*
X602501Y-24887D01*
X602877Y-24324D01*
X603016Y-23622D01*
X602877Y-22920D01*
X602479Y-22324D01*
X601883Y-21926D01*
X601181Y-21787D01*
D02*
G37*
G36*
X211024Y-19425D02*
X210321Y-19564D01*
X209726Y-19962D01*
X209328Y-20558D01*
X209188Y-21260D01*
X209328Y-21962D01*
X209726Y-22558D01*
X210321Y-22955D01*
X211024Y-23095D01*
X211726Y-22955D01*
X212321Y-22558D01*
X212719Y-21962D01*
X212859Y-21260D01*
X212719Y-20558D01*
X212321Y-19962D01*
X211726Y-19564D01*
X211024Y-19425D01*
D02*
G37*
G36*
X47441D02*
X46739Y-19564D01*
X46143Y-19962D01*
X45745Y-20558D01*
X45606Y-21260D01*
X45745Y-21962D01*
X46143Y-22558D01*
X46739Y-22955D01*
X47441Y-23095D01*
X48143Y-22955D01*
X48739Y-22558D01*
X49136Y-21962D01*
X49276Y-21260D01*
X49136Y-20558D01*
X48739Y-19962D01*
X48143Y-19564D01*
X47441Y-19425D01*
D02*
G37*
G36*
X116929Y-19818D02*
X116227Y-19958D01*
X115631Y-20356D01*
X115234Y-20951D01*
X115094Y-21654D01*
X115234Y-22356D01*
X115631Y-22951D01*
X116227Y-23349D01*
X116929Y-23489D01*
X117631Y-23349D01*
X118227Y-22951D01*
X118625Y-22356D01*
X118764Y-21654D01*
X118625Y-20951D01*
X118227Y-20356D01*
X117631Y-19958D01*
X116929Y-19818D01*
D02*
G37*
G36*
X138297Y-19551D02*
X137323Y-19745D01*
X136498Y-20297D01*
X135946Y-21122D01*
X135752Y-22096D01*
X135946Y-23070D01*
X136498Y-23896D01*
X137323Y-24447D01*
X138297Y-24641D01*
X139271Y-24447D01*
X140097Y-23896D01*
X140648Y-23070D01*
X140842Y-22096D01*
X140648Y-21122D01*
X140097Y-20297D01*
X139271Y-19745D01*
X138297Y-19551D01*
D02*
G37*
G36*
X505118Y-18244D02*
X504416Y-18383D01*
X503820Y-18781D01*
X503422Y-19376D01*
X503283Y-20079D01*
X503422Y-20781D01*
X503820Y-21376D01*
X504416Y-21774D01*
X504506Y-21792D01*
Y-22302D01*
X504416Y-22320D01*
X503820Y-22718D01*
X503422Y-23313D01*
X503283Y-24016D01*
X503422Y-24718D01*
X503820Y-25313D01*
X504416Y-25711D01*
X505118Y-25851D01*
X505820Y-25711D01*
X506416Y-25313D01*
X506814Y-24718D01*
X506953Y-24016D01*
X506814Y-23313D01*
X506416Y-22718D01*
X505820Y-22320D01*
X505730Y-22302D01*
Y-21792D01*
X505820Y-21774D01*
X506416Y-21376D01*
X506814Y-20781D01*
X506953Y-20079D01*
X506814Y-19376D01*
X506416Y-18781D01*
X505820Y-18383D01*
X505118Y-18244D01*
D02*
G37*
G36*
X496457D02*
X495754Y-18383D01*
X495159Y-18781D01*
X494761Y-19376D01*
X494621Y-20079D01*
X494761Y-20781D01*
X495159Y-21376D01*
X495754Y-21774D01*
X495845Y-21792D01*
Y-22302D01*
X495754Y-22320D01*
X495159Y-22718D01*
X494761Y-23313D01*
X494621Y-24016D01*
X494761Y-24718D01*
X495159Y-25313D01*
X495754Y-25711D01*
X496457Y-25851D01*
X497159Y-25711D01*
X497754Y-25313D01*
X498152Y-24718D01*
X498292Y-24016D01*
X498152Y-23313D01*
X497754Y-22718D01*
X497159Y-22320D01*
X497068Y-22302D01*
Y-21792D01*
X497159Y-21774D01*
X497754Y-21376D01*
X498152Y-20781D01*
X498292Y-20079D01*
X498152Y-19376D01*
X497754Y-18781D01*
X497159Y-18383D01*
X496457Y-18244D01*
D02*
G37*
G36*
X500787Y-22574D02*
X500085Y-22714D01*
X499490Y-23112D01*
X499092Y-23707D01*
X498952Y-24409D01*
X499092Y-25112D01*
X499490Y-25707D01*
X500085Y-26105D01*
X500787Y-26245D01*
X501490Y-26105D01*
X502085Y-25707D01*
X502483Y-25112D01*
X502623Y-24409D01*
X502483Y-23707D01*
X502085Y-23112D01*
X501490Y-22714D01*
X500787Y-22574D01*
D02*
G37*
G36*
X216535Y-23362D02*
X215833Y-23501D01*
X215238Y-23899D01*
X214840Y-24495D01*
X214700Y-25197D01*
X214840Y-25899D01*
X215238Y-26495D01*
X215833Y-26892D01*
X216535Y-27032D01*
X217238Y-26892D01*
X217833Y-26495D01*
X218231Y-25899D01*
X218371Y-25197D01*
X218231Y-24495D01*
X217833Y-23899D01*
X217238Y-23501D01*
X216535Y-23362D01*
D02*
G37*
G36*
X161417Y-24149D02*
X160715Y-24289D01*
X160120Y-24687D01*
X159722Y-25282D01*
X159582Y-25984D01*
X159722Y-26687D01*
X160120Y-27282D01*
X160715Y-27680D01*
X161417Y-27819D01*
X162120Y-27680D01*
X162715Y-27282D01*
X163113Y-26687D01*
X163253Y-25984D01*
X163113Y-25282D01*
X162715Y-24687D01*
X162120Y-24289D01*
X161417Y-24149D01*
D02*
G37*
G36*
X155328Y-24198D02*
X154625Y-24338D01*
X154030Y-24735D01*
X153632Y-25331D01*
X153492Y-26033D01*
X153632Y-26735D01*
X154030Y-27331D01*
X154625Y-27729D01*
X155328Y-27868D01*
X156030Y-27729D01*
X156625Y-27331D01*
X157023Y-26735D01*
X157163Y-26033D01*
X157023Y-25331D01*
X156625Y-24735D01*
X156030Y-24338D01*
X155328Y-24198D01*
D02*
G37*
G36*
X122539D02*
X121837Y-24338D01*
X121241Y-24735D01*
X120844Y-25331D01*
X120704Y-26033D01*
X120844Y-26735D01*
X121241Y-27331D01*
X121837Y-27729D01*
X122539Y-27868D01*
X123241Y-27729D01*
X123837Y-27331D01*
X124235Y-26735D01*
X124374Y-26033D01*
X124235Y-25331D01*
X123837Y-24735D01*
X123241Y-24338D01*
X122539Y-24198D01*
D02*
G37*
G36*
X47441Y-25527D02*
X46739Y-25667D01*
X46143Y-26065D01*
X45745Y-26660D01*
X45606Y-27362D01*
X45745Y-28065D01*
X46143Y-28660D01*
X46739Y-29058D01*
X47441Y-29197D01*
X48143Y-29058D01*
X48739Y-28660D01*
X49136Y-28065D01*
X49276Y-27362D01*
X49136Y-26660D01*
X48739Y-26065D01*
X48143Y-25667D01*
X47441Y-25527D01*
D02*
G37*
G36*
X39764Y-24149D02*
X39061Y-24289D01*
X38466Y-24687D01*
X38068Y-25282D01*
X37929Y-25984D01*
X38068Y-26687D01*
X38466Y-27282D01*
X38725Y-27455D01*
Y-28057D01*
X38466Y-28230D01*
X38068Y-28825D01*
X37929Y-29528D01*
X38068Y-30230D01*
X38466Y-30825D01*
X39061Y-31223D01*
X39764Y-31363D01*
X40466Y-31223D01*
X41061Y-30825D01*
X41459Y-30230D01*
X41599Y-29528D01*
X41459Y-28825D01*
X41061Y-28230D01*
X40802Y-28057D01*
Y-27455D01*
X41061Y-27282D01*
X41459Y-26687D01*
X41599Y-25984D01*
X41459Y-25282D01*
X41061Y-24687D01*
X40466Y-24289D01*
X39764Y-24149D01*
D02*
G37*
G36*
X100394Y-28480D02*
X99691Y-28619D01*
X99096Y-29017D01*
X98698Y-29613D01*
X98558Y-30315D01*
X98698Y-31017D01*
X99096Y-31613D01*
X99691Y-32010D01*
X100394Y-32150D01*
X101096Y-32010D01*
X101691Y-31613D01*
X102089Y-31017D01*
X102229Y-30315D01*
X102089Y-29613D01*
X101691Y-29017D01*
X101096Y-28619D01*
X100394Y-28480D01*
D02*
G37*
G36*
X121653Y-29661D02*
X120951Y-29801D01*
X120356Y-30198D01*
X119958Y-30794D01*
X119818Y-31496D01*
X119958Y-32198D01*
X120356Y-32794D01*
X120951Y-33192D01*
X121653Y-33331D01*
X122356Y-33192D01*
X122951Y-32794D01*
X123349Y-32198D01*
X123489Y-31496D01*
X123349Y-30794D01*
X122951Y-30198D01*
X122356Y-29801D01*
X121653Y-29661D01*
D02*
G37*
G36*
X226378Y-30842D02*
X225676Y-30982D01*
X225080Y-31380D01*
X224682Y-31975D01*
X224543Y-32677D01*
X224682Y-33380D01*
X225080Y-33975D01*
X225676Y-34373D01*
X226378Y-34512D01*
X227080Y-34373D01*
X227676Y-33975D01*
X228074Y-33380D01*
X228213Y-32677D01*
X228074Y-31975D01*
X227676Y-31380D01*
X227080Y-30982D01*
X226378Y-30842D01*
D02*
G37*
G36*
X155427Y-32072D02*
X154724Y-32212D01*
X154129Y-32609D01*
X153731Y-33205D01*
X153592Y-33907D01*
X153731Y-34609D01*
X154129Y-35205D01*
X154724Y-35603D01*
X155427Y-35742D01*
X156129Y-35603D01*
X156725Y-35205D01*
X157122Y-34609D01*
X157262Y-33907D01*
X157122Y-33205D01*
X156725Y-32609D01*
X156129Y-32212D01*
X155427Y-32072D01*
D02*
G37*
G36*
X43701Y-32810D02*
X42998Y-32950D01*
X42403Y-33348D01*
X42005Y-33943D01*
X41866Y-34646D01*
X42005Y-35348D01*
X42403Y-35943D01*
X42998Y-36341D01*
X43701Y-36481D01*
X44403Y-36341D01*
X44998Y-35943D01*
X45396Y-35348D01*
X45536Y-34646D01*
X45396Y-33943D01*
X44998Y-33348D01*
X44403Y-32950D01*
X43701Y-32810D01*
D02*
G37*
G36*
X91339Y-33204D02*
X90636Y-33344D01*
X90041Y-33742D01*
X89643Y-34337D01*
X89503Y-35039D01*
X89643Y-35742D01*
X90041Y-36337D01*
X90636Y-36735D01*
X91339Y-36875D01*
X92041Y-36735D01*
X92636Y-36337D01*
X93034Y-35742D01*
X93174Y-35039D01*
X93034Y-34337D01*
X92636Y-33742D01*
X92041Y-33344D01*
X91339Y-33204D01*
D02*
G37*
G36*
X295276Y-33598D02*
X294573Y-33737D01*
X293978Y-34135D01*
X293580Y-34731D01*
X293440Y-35433D01*
X293580Y-36135D01*
X293978Y-36731D01*
X294573Y-37129D01*
X295276Y-37268D01*
X295978Y-37129D01*
X296573Y-36731D01*
X296971Y-36135D01*
X297111Y-35433D01*
X296971Y-34731D01*
X296573Y-34135D01*
X295978Y-33737D01*
X295276Y-33598D01*
D02*
G37*
G36*
X290945D02*
X290243Y-33737D01*
X289647Y-34135D01*
X289249Y-34731D01*
X289110Y-35433D01*
X289249Y-36135D01*
X289647Y-36731D01*
X290243Y-37129D01*
X290945Y-37268D01*
X291647Y-37129D01*
X292243Y-36731D01*
X292640Y-36135D01*
X292780Y-35433D01*
X292640Y-34731D01*
X292243Y-34135D01*
X291647Y-33737D01*
X290945Y-33598D01*
D02*
G37*
G36*
X61417Y-33906D02*
X60715Y-34045D01*
X60120Y-34443D01*
X59722Y-35039D01*
X59582Y-35741D01*
X59722Y-36443D01*
X60120Y-37038D01*
X60715Y-37436D01*
X61417Y-37576D01*
X62120Y-37436D01*
X62715Y-37038D01*
X63113Y-36443D01*
X63253Y-35741D01*
X63113Y-35039D01*
X62715Y-34443D01*
X62120Y-34045D01*
X61417Y-33906D01*
D02*
G37*
G36*
X101181Y-36747D02*
X100479Y-36887D01*
X99883Y-37285D01*
X99485Y-37880D01*
X99346Y-38583D01*
X99485Y-39285D01*
X99883Y-39880D01*
X100479Y-40278D01*
X101181Y-40418D01*
X101883Y-40278D01*
X102479Y-39880D01*
X102877Y-39285D01*
X103016Y-38583D01*
X102877Y-37880D01*
X102479Y-37285D01*
X101883Y-36887D01*
X101181Y-36747D01*
D02*
G37*
G36*
X463779Y-37535D02*
X463077Y-37674D01*
X462482Y-38072D01*
X462084Y-38668D01*
X461944Y-39370D01*
X462084Y-40072D01*
X462482Y-40668D01*
X463077Y-41066D01*
X463779Y-41205D01*
X464482Y-41066D01*
X465077Y-40668D01*
X465475Y-40072D01*
X465615Y-39370D01*
X465475Y-38668D01*
X465077Y-38072D01*
X464482Y-37674D01*
X463779Y-37535D01*
D02*
G37*
G36*
X458661D02*
X457959Y-37674D01*
X457364Y-38072D01*
X456966Y-38668D01*
X456826Y-39370D01*
X456966Y-40072D01*
X457364Y-40668D01*
X457959Y-41066D01*
X458661Y-41205D01*
X459364Y-41066D01*
X459959Y-40668D01*
X460357Y-40072D01*
X460497Y-39370D01*
X460357Y-38668D01*
X459959Y-38072D01*
X459364Y-37674D01*
X458661Y-37535D01*
D02*
G37*
G36*
X86614D02*
X85912Y-37674D01*
X85316Y-38072D01*
X84919Y-38668D01*
X84779Y-39370D01*
X84919Y-40072D01*
X85316Y-40668D01*
X85912Y-41066D01*
X86614Y-41205D01*
X87317Y-41066D01*
X87912Y-40668D01*
X88310Y-40072D01*
X88449Y-39370D01*
X88310Y-38668D01*
X87912Y-38072D01*
X87317Y-37674D01*
X86614Y-37535D01*
D02*
G37*
G36*
X468898Y-37929D02*
X468195Y-38068D01*
X467600Y-38466D01*
X467202Y-39061D01*
X467062Y-39764D01*
X467202Y-40466D01*
X467600Y-41061D01*
X468195Y-41459D01*
X468898Y-41599D01*
X469600Y-41459D01*
X470195Y-41061D01*
X470593Y-40466D01*
X470733Y-39764D01*
X470593Y-39061D01*
X470195Y-38466D01*
X469600Y-38068D01*
X468898Y-37929D01*
D02*
G37*
G36*
X220866D02*
X220164Y-38068D01*
X219568Y-38466D01*
X219171Y-39061D01*
X219031Y-39764D01*
X219171Y-40466D01*
X219568Y-41061D01*
X220164Y-41459D01*
X220866Y-41599D01*
X221568Y-41459D01*
X222164Y-41061D01*
X222562Y-40466D01*
X222701Y-39764D01*
X222562Y-39061D01*
X222164Y-38466D01*
X221568Y-38068D01*
X220866Y-37929D01*
D02*
G37*
G36*
X295276Y-39110D02*
X294573Y-39249D01*
X293978Y-39647D01*
X293580Y-40243D01*
X293440Y-40945D01*
X293580Y-41647D01*
X293978Y-42243D01*
X294573Y-42640D01*
X295276Y-42780D01*
X295978Y-42640D01*
X296573Y-42243D01*
X296971Y-41647D01*
X297111Y-40945D01*
X296971Y-40243D01*
X296573Y-39647D01*
X295978Y-39249D01*
X295276Y-39110D01*
D02*
G37*
G36*
X290945D02*
X290243Y-39249D01*
X289647Y-39647D01*
X289249Y-40243D01*
X289110Y-40945D01*
X289249Y-41647D01*
X289647Y-42243D01*
X290243Y-42640D01*
X290945Y-42780D01*
X291647Y-42640D01*
X292243Y-42243D01*
X292640Y-41647D01*
X292780Y-40945D01*
X292640Y-40243D01*
X292243Y-39647D01*
X291647Y-39249D01*
X290945Y-39110D01*
D02*
G37*
G36*
X118504D02*
X117802Y-39249D01*
X117206Y-39647D01*
X116808Y-40243D01*
X116669Y-40945D01*
X116808Y-41647D01*
X117206Y-42243D01*
X117802Y-42640D01*
X118504Y-42780D01*
X119206Y-42640D01*
X119802Y-42243D01*
X120200Y-41647D01*
X120339Y-40945D01*
X120200Y-40243D01*
X119802Y-39647D01*
X119206Y-39249D01*
X118504Y-39110D01*
D02*
G37*
G36*
X157087Y-39897D02*
X156384Y-40037D01*
X155789Y-40435D01*
X155391Y-41030D01*
X155251Y-41732D01*
X155391Y-42435D01*
X155789Y-43030D01*
X156384Y-43428D01*
X157087Y-43567D01*
X157789Y-43428D01*
X158384Y-43030D01*
X158782Y-42435D01*
X158922Y-41732D01*
X158782Y-41030D01*
X158384Y-40435D01*
X157789Y-40037D01*
X157087Y-39897D01*
D02*
G37*
G36*
X544095Y-40291D02*
X543392Y-40430D01*
X542797Y-40828D01*
X542399Y-41424D01*
X542259Y-42126D01*
X542399Y-42828D01*
X542797Y-43424D01*
X543392Y-43821D01*
X544095Y-43961D01*
X544797Y-43821D01*
X545392Y-43424D01*
X545790Y-42828D01*
X545930Y-42126D01*
X545790Y-41424D01*
X545392Y-40828D01*
X544797Y-40430D01*
X544095Y-40291D01*
D02*
G37*
G36*
X539764D02*
X539061Y-40430D01*
X538466Y-40828D01*
X538068Y-41424D01*
X537928Y-42126D01*
X538068Y-42828D01*
X538466Y-43424D01*
X539061Y-43821D01*
X539764Y-43961D01*
X540466Y-43821D01*
X541061Y-43424D01*
X541459Y-42828D01*
X541599Y-42126D01*
X541459Y-41424D01*
X541061Y-40828D01*
X540466Y-40430D01*
X539764Y-40291D01*
D02*
G37*
G36*
X215354D02*
X214652Y-40430D01*
X214057Y-40828D01*
X213659Y-41424D01*
X213519Y-42126D01*
X213659Y-42828D01*
X214057Y-43424D01*
X214652Y-43821D01*
X215354Y-43961D01*
X216057Y-43821D01*
X216652Y-43424D01*
X217050Y-42828D01*
X217190Y-42126D01*
X217050Y-41424D01*
X216652Y-40828D01*
X216057Y-40430D01*
X215354Y-40291D01*
D02*
G37*
G36*
X324016Y-33992D02*
X323313Y-34131D01*
X322718Y-34529D01*
X322320Y-35124D01*
X322181Y-35827D01*
X322320Y-36529D01*
X322718Y-37124D01*
X323313Y-37522D01*
X323404Y-37540D01*
Y-38050D01*
X323313Y-38068D01*
X322718Y-38466D01*
X322320Y-39061D01*
X322181Y-39764D01*
X322320Y-40466D01*
X322718Y-41061D01*
X322759Y-41089D01*
Y-41589D01*
X322718Y-41616D01*
X322320Y-42211D01*
X322181Y-42913D01*
X322320Y-43616D01*
X322718Y-44211D01*
X323313Y-44609D01*
X324016Y-44749D01*
X324718Y-44609D01*
X325313Y-44211D01*
X325711Y-43616D01*
X325851Y-42913D01*
X325711Y-42211D01*
X325313Y-41616D01*
X325273Y-41589D01*
Y-41089D01*
X325313Y-41061D01*
X325711Y-40466D01*
X325851Y-39764D01*
X325711Y-39061D01*
X325313Y-38466D01*
X324718Y-38068D01*
X324627Y-38050D01*
Y-37540D01*
X324718Y-37522D01*
X325313Y-37124D01*
X325711Y-36529D01*
X325851Y-35827D01*
X325711Y-35124D01*
X325313Y-34529D01*
X324718Y-34131D01*
X324016Y-33992D01*
D02*
G37*
G36*
X318898D02*
X318195Y-34131D01*
X317600Y-34529D01*
X317202Y-35124D01*
X317062Y-35827D01*
X317202Y-36529D01*
X317600Y-37124D01*
X318195Y-37522D01*
X318286Y-37540D01*
Y-38050D01*
X318195Y-38068D01*
X317600Y-38466D01*
X317202Y-39061D01*
X317062Y-39764D01*
X317202Y-40466D01*
X317600Y-41061D01*
X317859Y-41235D01*
Y-41836D01*
X317600Y-42009D01*
X317202Y-42605D01*
X317062Y-43307D01*
X317202Y-44009D01*
X317600Y-44605D01*
X318195Y-45003D01*
X318898Y-45142D01*
X319600Y-45003D01*
X320195Y-44605D01*
X320593Y-44009D01*
X320733Y-43307D01*
X320593Y-42605D01*
X320195Y-42009D01*
X319936Y-41836D01*
Y-41235D01*
X320195Y-41061D01*
X320593Y-40466D01*
X320733Y-39764D01*
X320593Y-39061D01*
X320195Y-38466D01*
X319600Y-38068D01*
X319509Y-38050D01*
Y-37540D01*
X319600Y-37522D01*
X320195Y-37124D01*
X320593Y-36529D01*
X320733Y-35827D01*
X320593Y-35124D01*
X320195Y-34529D01*
X319600Y-34131D01*
X318898Y-33992D01*
D02*
G37*
G36*
X37402Y-41520D02*
X36699Y-41660D01*
X36104Y-42058D01*
X35706Y-42653D01*
X35566Y-43355D01*
X35706Y-44058D01*
X36104Y-44653D01*
X36699Y-45051D01*
X37402Y-45191D01*
X38104Y-45051D01*
X38699Y-44653D01*
X39097Y-44058D01*
X39237Y-43355D01*
X39097Y-42653D01*
X38699Y-42058D01*
X38104Y-41660D01*
X37402Y-41520D01*
D02*
G37*
G36*
X88583Y-44621D02*
X87880Y-44761D01*
X87285Y-45159D01*
X86980Y-45615D01*
X86528Y-45677D01*
X86402Y-45649D01*
X86337Y-45553D01*
X85742Y-45155D01*
X85039Y-45015D01*
X84337Y-45155D01*
X83742Y-45553D01*
X83344Y-46148D01*
X83204Y-46850D01*
X83344Y-47553D01*
X83742Y-48148D01*
X84337Y-48546D01*
X84428Y-48564D01*
Y-49074D01*
X84337Y-49092D01*
X83742Y-49490D01*
X83344Y-50085D01*
X83204Y-50787D01*
X83344Y-51490D01*
X83742Y-52085D01*
X83782Y-52112D01*
Y-52612D01*
X83742Y-52639D01*
X83344Y-53235D01*
X83204Y-53937D01*
X83344Y-54639D01*
X83742Y-55235D01*
X84337Y-55633D01*
X84890Y-55743D01*
X84779Y-56299D01*
X84919Y-57002D01*
X85316Y-57597D01*
X85912Y-57995D01*
X86614Y-58135D01*
X87317Y-57995D01*
X87912Y-57597D01*
X88310Y-57002D01*
X88449Y-56299D01*
X88432Y-56213D01*
X88781Y-55733D01*
X89285Y-55633D01*
X89880Y-55235D01*
X90278Y-54639D01*
X90418Y-53937D01*
X90278Y-53235D01*
X89880Y-52639D01*
X89840Y-52612D01*
Y-52112D01*
X89880Y-52085D01*
X90278Y-51490D01*
X90418Y-50787D01*
X90278Y-50085D01*
X89880Y-49490D01*
X89285Y-49092D01*
X88583Y-48952D01*
X87880Y-49092D01*
X87285Y-49490D01*
X87112Y-49749D01*
X86510D01*
X86337Y-49490D01*
X85742Y-49092D01*
X85651Y-49074D01*
Y-48564D01*
X85742Y-48546D01*
X86337Y-48148D01*
X86642Y-47692D01*
X87094Y-47630D01*
X87220Y-47658D01*
X87285Y-47754D01*
X87880Y-48152D01*
X88583Y-48292D01*
X89285Y-48152D01*
X89880Y-47754D01*
X90278Y-47159D01*
X90418Y-46457D01*
X90278Y-45754D01*
X89880Y-45159D01*
X89285Y-44761D01*
X88583Y-44621D01*
D02*
G37*
G36*
X458661Y-42259D02*
X457959Y-42399D01*
X457364Y-42797D01*
X456966Y-43392D01*
X456826Y-44094D01*
X456966Y-44797D01*
X457364Y-45392D01*
X457959Y-45790D01*
X458661Y-45930D01*
X459364Y-45790D01*
X459959Y-45392D01*
X460357Y-44797D01*
X460497Y-44094D01*
X460357Y-43392D01*
X459959Y-42797D01*
X459364Y-42399D01*
X458661Y-42259D01*
D02*
G37*
G36*
X210236D02*
X209534Y-42399D01*
X208939Y-42797D01*
X208541Y-43392D01*
X208401Y-44094D01*
X208541Y-44797D01*
X208939Y-45392D01*
X209534Y-45790D01*
X210236Y-45930D01*
X210939Y-45790D01*
X211534Y-45392D01*
X211932Y-44797D01*
X212071Y-44094D01*
X211932Y-43392D01*
X211534Y-42797D01*
X210939Y-42399D01*
X210236Y-42259D01*
D02*
G37*
G36*
X468504Y-42653D02*
X467802Y-42793D01*
X467206Y-43191D01*
X466808Y-43786D01*
X466669Y-44488D01*
X466808Y-45191D01*
X467206Y-45786D01*
X467802Y-46184D01*
X468504Y-46323D01*
X469206Y-46184D01*
X469802Y-45786D01*
X470199Y-45191D01*
X470339Y-44488D01*
X470199Y-43786D01*
X469802Y-43191D01*
X469206Y-42793D01*
X468504Y-42653D01*
D02*
G37*
G36*
X463779D02*
X463077Y-42793D01*
X462482Y-43191D01*
X462084Y-43786D01*
X461944Y-44488D01*
X462084Y-45191D01*
X462482Y-45786D01*
X463077Y-46184D01*
X463779Y-46323D01*
X464482Y-46184D01*
X465077Y-45786D01*
X465475Y-45191D01*
X465615Y-44488D01*
X465475Y-43786D01*
X465077Y-43191D01*
X464482Y-42793D01*
X463779Y-42653D01*
D02*
G37*
G36*
X295669Y-43440D02*
X294967Y-43580D01*
X294372Y-43978D01*
X293974Y-44573D01*
X293834Y-45276D01*
X293974Y-45978D01*
X294372Y-46573D01*
X294967Y-46971D01*
X295669Y-47111D01*
X296372Y-46971D01*
X296967Y-46573D01*
X297365Y-45978D01*
X297504Y-45276D01*
X297365Y-44573D01*
X296967Y-43978D01*
X296372Y-43580D01*
X295669Y-43440D01*
D02*
G37*
G36*
X290945D02*
X290243Y-43580D01*
X289647Y-43978D01*
X289249Y-44573D01*
X289110Y-45276D01*
X289249Y-45978D01*
X289647Y-46573D01*
X290243Y-46971D01*
X290945Y-47111D01*
X291647Y-46971D01*
X292243Y-46573D01*
X292640Y-45978D01*
X292780Y-45276D01*
X292640Y-44573D01*
X292243Y-43978D01*
X291647Y-43580D01*
X290945Y-43440D01*
D02*
G37*
G36*
X38382Y-46520D02*
X37680Y-46660D01*
X37084Y-47058D01*
X36686Y-47653D01*
X36547Y-48355D01*
X36641Y-48828D01*
X36191Y-49129D01*
X36135Y-49092D01*
X35433Y-48952D01*
X34731Y-49092D01*
X34135Y-49490D01*
X33737Y-50085D01*
X33598Y-50787D01*
X33737Y-51490D01*
X34135Y-52085D01*
X34731Y-52483D01*
X35433Y-52623D01*
X36135Y-52483D01*
X36657Y-52135D01*
X36731Y-52085D01*
X37083Y-52406D01*
X37051Y-52453D01*
X36917Y-52653D01*
X36778Y-53355D01*
X36917Y-54058D01*
X37315Y-54653D01*
X37911Y-55051D01*
X38613Y-55191D01*
X39315Y-55051D01*
X39911Y-54653D01*
X40308Y-54058D01*
X40448Y-53355D01*
X40308Y-52653D01*
X39911Y-52058D01*
X39315Y-51660D01*
X38613Y-51520D01*
X37911Y-51660D01*
X37389Y-52008D01*
X37315Y-52058D01*
X36963Y-51737D01*
X36995Y-51689D01*
X37129Y-51490D01*
X37268Y-50787D01*
X37174Y-50315D01*
X37624Y-50014D01*
X37680Y-50051D01*
X38382Y-50191D01*
X39084Y-50051D01*
X39680Y-49653D01*
X40077Y-49058D01*
X40217Y-48355D01*
X40077Y-47653D01*
X39680Y-47058D01*
X39084Y-46660D01*
X38382Y-46520D01*
D02*
G37*
G36*
X616142Y-45803D02*
X615439Y-45942D01*
X614844Y-46340D01*
X614446Y-46935D01*
X614306Y-47638D01*
X614446Y-48340D01*
X614844Y-48935D01*
X615439Y-49333D01*
X616142Y-49473D01*
X616844Y-49333D01*
X617440Y-48935D01*
X617837Y-48340D01*
X617977Y-47638D01*
X617837Y-46935D01*
X617440Y-46340D01*
X616844Y-45942D01*
X616142Y-45803D01*
D02*
G37*
G36*
X613386Y-48952D02*
X612683Y-49092D01*
X612088Y-49490D01*
X611690Y-50085D01*
X611663Y-50223D01*
X611134Y-50317D01*
X610845Y-49883D01*
X610250Y-49485D01*
X609547Y-49346D01*
X608845Y-49485D01*
X608252Y-49882D01*
X607991Y-49490D01*
X607395Y-49092D01*
X606693Y-48952D01*
X605991Y-49092D01*
X605395Y-49490D01*
X604997Y-50085D01*
X604858Y-50787D01*
X604997Y-51490D01*
X605395Y-52085D01*
X605991Y-52483D01*
X606693Y-52623D01*
X607395Y-52483D01*
X607988Y-52087D01*
X608250Y-52479D01*
X608845Y-52877D01*
X609547Y-53016D01*
X610250Y-52877D01*
X610845Y-52479D01*
X611243Y-51883D01*
X611270Y-51746D01*
X611799Y-51652D01*
X612088Y-52085D01*
X612683Y-52483D01*
X613386Y-52623D01*
X614088Y-52483D01*
X614684Y-52085D01*
X615081Y-51490D01*
X615221Y-50787D01*
X615081Y-50085D01*
X614684Y-49490D01*
X614088Y-49092D01*
X613386Y-48952D01*
D02*
G37*
G36*
X599213Y-48165D02*
X598510Y-48304D01*
X597915Y-48702D01*
X597517Y-49298D01*
X597377Y-50000D01*
X597517Y-50702D01*
X597915Y-51298D01*
X598510Y-51696D01*
X599213Y-51835D01*
X599915Y-51696D01*
X600510Y-51298D01*
X600908Y-50702D01*
X601048Y-50000D01*
X600908Y-49298D01*
X600510Y-48702D01*
X599915Y-48304D01*
X599213Y-48165D01*
D02*
G37*
G36*
X618898Y-48952D02*
X618195Y-49092D01*
X617600Y-49490D01*
X617202Y-50085D01*
X617062Y-50787D01*
X617202Y-51490D01*
X617600Y-52085D01*
X618195Y-52483D01*
X618898Y-52623D01*
X619600Y-52483D01*
X620195Y-52085D01*
X620593Y-51490D01*
X620733Y-50787D01*
X620593Y-50085D01*
X620195Y-49490D01*
X619600Y-49092D01*
X618898Y-48952D01*
D02*
G37*
G36*
X534646Y-40291D02*
X533943Y-40430D01*
X533348Y-40828D01*
X532950Y-41424D01*
X532810Y-42126D01*
X532950Y-42828D01*
X533348Y-43424D01*
X533389Y-43451D01*
Y-43951D01*
X533348Y-43978D01*
X532950Y-44573D01*
X532810Y-45276D01*
X532950Y-45978D01*
X533226Y-46391D01*
X533348Y-46573D01*
X533116Y-47019D01*
X532954Y-47128D01*
X532556Y-47723D01*
X532417Y-48425D01*
X532556Y-49128D01*
X532954Y-49723D01*
X533410Y-50028D01*
X533472Y-50480D01*
X533445Y-50606D01*
X533348Y-50671D01*
X532950Y-51266D01*
X532810Y-51968D01*
X532950Y-52671D01*
X533348Y-53266D01*
X533943Y-53664D01*
X534646Y-53804D01*
X535348Y-53664D01*
X535943Y-53266D01*
X536341Y-52671D01*
X536481Y-51968D01*
X536341Y-51266D01*
X535943Y-50671D01*
X535487Y-50366D01*
X535426Y-49914D01*
X535453Y-49788D01*
X535550Y-49723D01*
X535948Y-49128D01*
X536087Y-48425D01*
X535948Y-47723D01*
X535672Y-47310D01*
X535550Y-47128D01*
X535782Y-46681D01*
X535943Y-46573D01*
X536341Y-45978D01*
X536481Y-45276D01*
X536341Y-44573D01*
X535943Y-43978D01*
X535903Y-43951D01*
Y-43451D01*
X535943Y-43424D01*
X536341Y-42828D01*
X536481Y-42126D01*
X536341Y-41424D01*
X535943Y-40828D01*
X535348Y-40430D01*
X534646Y-40291D01*
D02*
G37*
G36*
X121653Y-50921D02*
X120951Y-51060D01*
X120356Y-51458D01*
X119958Y-52054D01*
X119818Y-52756D01*
X119958Y-53458D01*
X120356Y-54054D01*
X120951Y-54452D01*
X121653Y-54591D01*
X122356Y-54452D01*
X122951Y-54054D01*
X123349Y-53458D01*
X123489Y-52756D01*
X123349Y-52054D01*
X122951Y-51458D01*
X122356Y-51060D01*
X121653Y-50921D01*
D02*
G37*
G36*
X210630Y-51314D02*
X209928Y-51454D01*
X209332Y-51852D01*
X208934Y-52447D01*
X208795Y-53150D01*
X208934Y-53852D01*
X209332Y-54447D01*
X209928Y-54845D01*
X210630Y-54985D01*
X211332Y-54845D01*
X211928Y-54447D01*
X212326Y-53852D01*
X212465Y-53150D01*
X212326Y-52447D01*
X211928Y-51852D01*
X211332Y-51454D01*
X210630Y-51314D01*
D02*
G37*
G36*
X601575Y-51708D02*
X600873Y-51848D01*
X600277Y-52246D01*
X599879Y-52841D01*
X599740Y-53543D01*
X599879Y-54246D01*
X600277Y-54841D01*
X600873Y-55239D01*
X601575Y-55379D01*
X602277Y-55239D01*
X602873Y-54841D01*
X603270Y-54246D01*
X603410Y-53543D01*
X603270Y-52841D01*
X602873Y-52246D01*
X602277Y-51848D01*
X601575Y-51708D01*
D02*
G37*
G36*
X138297Y-51047D02*
X137323Y-51241D01*
X136498Y-51793D01*
X135946Y-52618D01*
X135752Y-53592D01*
X135946Y-54566D01*
X136498Y-55392D01*
X137323Y-55943D01*
X138297Y-56137D01*
X139271Y-55943D01*
X140097Y-55392D01*
X140648Y-54566D01*
X140842Y-53592D01*
X140648Y-52618D01*
X140097Y-51793D01*
X139271Y-51241D01*
X138297Y-51047D01*
D02*
G37*
G36*
X152756Y-55645D02*
X152054Y-55785D01*
X151458Y-56183D01*
X151060Y-56778D01*
X150921Y-57480D01*
X151060Y-58183D01*
X151458Y-58778D01*
X152054Y-59176D01*
X152756Y-59316D01*
X153458Y-59176D01*
X154054Y-58778D01*
X154452Y-58183D01*
X154591Y-57480D01*
X154452Y-56778D01*
X154054Y-56183D01*
X153458Y-55785D01*
X152756Y-55645D01*
D02*
G37*
G36*
X121457Y-55694D02*
X120754Y-55834D01*
X120159Y-56231D01*
X119761Y-56827D01*
X119622Y-57529D01*
X119761Y-58232D01*
X120159Y-58827D01*
X120754Y-59225D01*
X121457Y-59364D01*
X122159Y-59225D01*
X122754Y-58827D01*
X123152Y-58232D01*
X123292Y-57529D01*
X123152Y-56827D01*
X122754Y-56231D01*
X122159Y-55834D01*
X121457Y-55694D01*
D02*
G37*
G36*
X38583Y-56520D02*
X37880Y-56660D01*
X37285Y-57058D01*
X36887Y-57653D01*
X36747Y-58355D01*
X36887Y-59058D01*
X37285Y-59653D01*
X37880Y-60051D01*
X38583Y-60191D01*
X39285Y-60051D01*
X39880Y-59653D01*
X40278Y-59058D01*
X40418Y-58355D01*
X40278Y-57653D01*
X39880Y-57058D01*
X39285Y-56660D01*
X38583Y-56520D01*
D02*
G37*
G36*
X209541Y-56854D02*
X208839Y-56994D01*
X208244Y-57391D01*
X207846Y-57987D01*
X207706Y-58689D01*
X207846Y-59391D01*
X208244Y-59987D01*
X208839Y-60385D01*
X209541Y-60524D01*
X210244Y-60385D01*
X210839Y-59987D01*
X211237Y-59391D01*
X211377Y-58689D01*
X211237Y-57987D01*
X210839Y-57391D01*
X210244Y-56994D01*
X209541Y-56854D01*
D02*
G37*
G36*
X618110Y-60369D02*
X617408Y-60509D01*
X616813Y-60907D01*
X616415Y-61502D01*
X616275Y-62205D01*
X616415Y-62907D01*
X616813Y-63502D01*
X617408Y-63900D01*
X618110Y-64040D01*
X618813Y-63900D01*
X619408Y-63502D01*
X619806Y-62907D01*
X619945Y-62205D01*
X619806Y-61502D01*
X619408Y-60907D01*
X618813Y-60509D01*
X618110Y-60369D01*
D02*
G37*
G36*
X66102Y-62249D02*
X65400Y-62389D01*
X64805Y-62787D01*
X64407Y-63382D01*
X64267Y-64085D01*
X64407Y-64787D01*
X64805Y-65382D01*
X65400Y-65780D01*
X66102Y-65920D01*
X66805Y-65780D01*
X67400Y-65382D01*
X67798Y-64787D01*
X67938Y-64085D01*
X67798Y-63382D01*
X67400Y-62787D01*
X66805Y-62389D01*
X66102Y-62249D01*
D02*
G37*
G36*
X152756Y-63519D02*
X152054Y-63659D01*
X151458Y-64057D01*
X151060Y-64652D01*
X150921Y-65354D01*
X151060Y-66057D01*
X151458Y-66652D01*
X152054Y-67050D01*
X152756Y-67190D01*
X153458Y-67050D01*
X154054Y-66652D01*
X154452Y-66057D01*
X154591Y-65354D01*
X154452Y-64652D01*
X154054Y-64057D01*
X153458Y-63659D01*
X152756Y-63519D01*
D02*
G37*
G36*
X117323D02*
X116621Y-63659D01*
X116025Y-64057D01*
X115627Y-64652D01*
X115488Y-65354D01*
X115627Y-66057D01*
X116025Y-66652D01*
X116621Y-67050D01*
X117323Y-67190D01*
X118025Y-67050D01*
X118621Y-66652D01*
X119018Y-66057D01*
X119158Y-65354D01*
X119018Y-64652D01*
X118621Y-64057D01*
X118025Y-63659D01*
X117323Y-63519D01*
D02*
G37*
G36*
X-23622Y-58204D02*
X-24324Y-58344D01*
X-24920Y-58742D01*
X-25318Y-59337D01*
X-25457Y-60039D01*
X-25318Y-60742D01*
X-25032Y-61168D01*
X-24958Y-61516D01*
X-25032Y-61863D01*
X-25318Y-62290D01*
X-25457Y-62992D01*
X-25318Y-63694D01*
X-24920Y-64290D01*
X-24324Y-64688D01*
X-24234Y-64706D01*
Y-65215D01*
X-24324Y-65234D01*
X-24920Y-65631D01*
X-25318Y-66227D01*
X-25457Y-66929D01*
X-25318Y-67631D01*
X-24920Y-68227D01*
X-24324Y-68625D01*
X-23622Y-68764D01*
X-22920Y-68625D01*
X-22324Y-68227D01*
X-21926Y-67631D01*
X-21787Y-66929D01*
X-21926Y-66227D01*
X-22324Y-65631D01*
X-22920Y-65234D01*
X-23010Y-65215D01*
Y-64706D01*
X-22920Y-64688D01*
X-22324Y-64290D01*
X-21926Y-63694D01*
X-21787Y-62992D01*
X-21926Y-62290D01*
X-22212Y-61863D01*
X-22286Y-61516D01*
X-22212Y-61168D01*
X-21926Y-60742D01*
X-21787Y-60039D01*
X-21926Y-59337D01*
X-22324Y-58742D01*
X-22920Y-58344D01*
X-23622Y-58204D01*
D02*
G37*
G36*
X326772Y-67456D02*
X326069Y-67596D01*
X325474Y-67994D01*
X325076Y-68589D01*
X324936Y-69291D01*
X325076Y-69994D01*
X325474Y-70589D01*
X326069Y-70987D01*
X326772Y-71127D01*
X327474Y-70987D01*
X328069Y-70589D01*
X328467Y-69994D01*
X328607Y-69291D01*
X328467Y-68589D01*
X328069Y-67994D01*
X327474Y-67596D01*
X326772Y-67456D01*
D02*
G37*
G36*
X322441D02*
X321739Y-67596D01*
X321143Y-67994D01*
X320745Y-68589D01*
X320606Y-69291D01*
X320745Y-69994D01*
X321143Y-70589D01*
X321739Y-70987D01*
X322441Y-71127D01*
X323143Y-70987D01*
X323739Y-70589D01*
X324136Y-69994D01*
X324276Y-69291D01*
X324136Y-68589D01*
X323739Y-67994D01*
X323143Y-67596D01*
X322441Y-67456D01*
D02*
G37*
G36*
X138297Y-66795D02*
X137323Y-66989D01*
X136498Y-67541D01*
X135946Y-68366D01*
X135752Y-69340D01*
X135946Y-70314D01*
X136498Y-71140D01*
X137323Y-71691D01*
X138297Y-71885D01*
X139271Y-71691D01*
X140097Y-71140D01*
X140648Y-70314D01*
X140842Y-69340D01*
X140648Y-68366D01*
X140097Y-67541D01*
X139271Y-66989D01*
X138297Y-66795D01*
D02*
G37*
G36*
X246063Y-68243D02*
X245361Y-68383D01*
X244765Y-68781D01*
X244367Y-69376D01*
X244228Y-70079D01*
X244367Y-70781D01*
X244765Y-71377D01*
X245312Y-71742D01*
X245327Y-71934D01*
X245259Y-72262D01*
X244967Y-72320D01*
X244372Y-72718D01*
X243974Y-73313D01*
X243956Y-73404D01*
X243446D01*
X243428Y-73313D01*
X243030Y-72718D01*
X242435Y-72320D01*
X242344Y-72302D01*
Y-71792D01*
X242435Y-71774D01*
X243030Y-71377D01*
X243428Y-70781D01*
X243567Y-70079D01*
X243428Y-69376D01*
X243030Y-68781D01*
X242435Y-68383D01*
X241732Y-68243D01*
X241030Y-68383D01*
X240435Y-68781D01*
X240037Y-69376D01*
X239897Y-70079D01*
X240037Y-70781D01*
X240435Y-71377D01*
X241030Y-71774D01*
X241121Y-71792D01*
Y-72302D01*
X241030Y-72320D01*
X240435Y-72718D01*
X240037Y-73313D01*
X239897Y-74016D01*
X240037Y-74718D01*
X240435Y-75314D01*
X241030Y-75711D01*
X241732Y-75851D01*
X242435Y-75711D01*
X243030Y-75314D01*
X243428Y-74718D01*
X243446Y-74627D01*
X243956D01*
X243974Y-74718D01*
X244372Y-75314D01*
X244967Y-75711D01*
X245669Y-75851D01*
X246372Y-75711D01*
X246967Y-75314D01*
X247365Y-74718D01*
X247505Y-74016D01*
X247365Y-73313D01*
X246967Y-72718D01*
X246420Y-72353D01*
X246405Y-72160D01*
X246473Y-71832D01*
X246765Y-71774D01*
X247361Y-71377D01*
X247759Y-70781D01*
X247898Y-70079D01*
X247759Y-69376D01*
X247361Y-68781D01*
X246765Y-68383D01*
X246063Y-68243D01*
D02*
G37*
G36*
X317717Y-67456D02*
X317014Y-67596D01*
X316419Y-67994D01*
X316021Y-68589D01*
X315881Y-69291D01*
X316021Y-69994D01*
X316419Y-70589D01*
X317014Y-70987D01*
X317105Y-71005D01*
Y-71515D01*
X317014Y-71533D01*
X316419Y-71931D01*
X316021Y-72526D01*
X315881Y-73228D01*
X316021Y-73931D01*
X316419Y-74526D01*
X317014Y-74924D01*
X317717Y-75064D01*
X318419Y-74924D01*
X319014Y-74526D01*
X319412Y-73931D01*
X319552Y-73228D01*
X319412Y-72526D01*
X319014Y-71931D01*
X318419Y-71533D01*
X318328Y-71515D01*
Y-71005D01*
X318419Y-70987D01*
X319014Y-70589D01*
X319412Y-69994D01*
X319552Y-69291D01*
X319412Y-68589D01*
X319014Y-67994D01*
X318419Y-67596D01*
X317717Y-67456D01*
D02*
G37*
G36*
X157480Y-71393D02*
X156778Y-71533D01*
X156183Y-71931D01*
X155785Y-72526D01*
X155645Y-73228D01*
X155785Y-73931D01*
X156183Y-74526D01*
X156778Y-74924D01*
X157480Y-75064D01*
X158183Y-74924D01*
X158778Y-74526D01*
X159176Y-73931D01*
X159316Y-73228D01*
X159176Y-72526D01*
X158778Y-71931D01*
X158183Y-71533D01*
X157480Y-71393D01*
D02*
G37*
G36*
X326772Y-71787D02*
X326069Y-71926D01*
X325474Y-72324D01*
X325076Y-72920D01*
X324936Y-73622D01*
X325076Y-74324D01*
X325474Y-74920D01*
X326069Y-75318D01*
X326772Y-75457D01*
X327474Y-75318D01*
X328069Y-74920D01*
X328467Y-74324D01*
X328607Y-73622D01*
X328467Y-72920D01*
X328069Y-72324D01*
X327474Y-71926D01*
X326772Y-71787D01*
D02*
G37*
G36*
X322441D02*
X321739Y-71926D01*
X321143Y-72324D01*
X320745Y-72920D01*
X320606Y-73622D01*
X320745Y-74324D01*
X321143Y-74920D01*
X321739Y-75318D01*
X322441Y-75457D01*
X323143Y-75318D01*
X323739Y-74920D01*
X324136Y-74324D01*
X324276Y-73622D01*
X324136Y-72920D01*
X323739Y-72324D01*
X323143Y-71926D01*
X322441Y-71787D01*
D02*
G37*
G36*
X209449Y-70212D02*
X208747Y-70352D01*
X208151Y-70749D01*
X207753Y-71345D01*
X207614Y-72047D01*
X207753Y-72750D01*
X208073Y-73228D01*
X207753Y-73707D01*
X207614Y-74410D01*
X207753Y-75112D01*
X208151Y-75707D01*
X208747Y-76105D01*
X209449Y-76245D01*
X210151Y-76105D01*
X210747Y-75707D01*
X211144Y-75112D01*
X211284Y-74410D01*
X211144Y-73707D01*
X210824Y-73228D01*
X211144Y-72750D01*
X211284Y-72047D01*
X211144Y-71345D01*
X210747Y-70749D01*
X210151Y-70352D01*
X209449Y-70212D01*
D02*
G37*
G36*
X121467Y-72739D02*
X120764Y-72879D01*
X120169Y-73277D01*
X119771Y-73872D01*
X119631Y-74575D01*
X119771Y-75277D01*
X120169Y-75872D01*
X120764Y-76270D01*
X121467Y-76410D01*
X122169Y-76270D01*
X122764Y-75872D01*
X123162Y-75277D01*
X123302Y-74575D01*
X123162Y-73872D01*
X122764Y-73277D01*
X122169Y-72879D01*
X121467Y-72739D01*
D02*
G37*
G36*
X462992Y-74543D02*
X462290Y-74682D01*
X461694Y-75080D01*
X461297Y-75676D01*
X461157Y-76378D01*
X461297Y-77080D01*
X461694Y-77676D01*
X462290Y-78074D01*
X462992Y-78213D01*
X463694Y-78074D01*
X464290Y-77676D01*
X464688Y-77080D01*
X464827Y-76378D01*
X464688Y-75676D01*
X464290Y-75080D01*
X463694Y-74682D01*
X462992Y-74543D01*
D02*
G37*
G36*
X85039Y-75724D02*
X84337Y-75863D01*
X83742Y-76261D01*
X83344Y-76857D01*
X83204Y-77559D01*
X83344Y-78261D01*
X83742Y-78857D01*
X84337Y-79255D01*
X85039Y-79394D01*
X85742Y-79255D01*
X86337Y-78857D01*
X86735Y-78261D01*
X86875Y-77559D01*
X86735Y-76857D01*
X86337Y-76261D01*
X85742Y-75863D01*
X85039Y-75724D01*
D02*
G37*
G36*
X194882Y-75154D02*
X194056Y-75263D01*
X193286Y-75582D01*
X192624Y-76089D01*
X192117Y-76750D01*
X191798Y-77520D01*
X191689Y-78347D01*
X191798Y-79173D01*
X192117Y-79943D01*
X192624Y-80604D01*
X193286Y-81111D01*
X194056Y-81430D01*
X194882Y-81539D01*
X195708Y-81430D01*
X196478Y-81111D01*
X197139Y-80604D01*
X197647Y-79943D01*
X197966Y-79173D01*
X198074Y-78347D01*
X197966Y-77520D01*
X197647Y-76750D01*
X197139Y-76089D01*
X196478Y-75582D01*
X195708Y-75263D01*
X194882Y-75154D01*
D02*
G37*
G36*
X149606Y-78480D02*
X148904Y-78619D01*
X148309Y-79017D01*
X147911Y-79613D01*
X147771Y-80315D01*
X147911Y-81017D01*
X148309Y-81613D01*
X148904Y-82011D01*
X149606Y-82150D01*
X150309Y-82011D01*
X150904Y-81613D01*
X151302Y-81017D01*
X151442Y-80315D01*
X151302Y-79613D01*
X150904Y-79017D01*
X150309Y-78619D01*
X149606Y-78480D01*
D02*
G37*
G36*
X608268Y-82417D02*
X607565Y-82556D01*
X606970Y-82954D01*
X606572Y-83550D01*
X606432Y-84252D01*
X606572Y-84954D01*
X606970Y-85550D01*
X607565Y-85948D01*
X608268Y-86087D01*
X608970Y-85948D01*
X609565Y-85550D01*
X609963Y-84954D01*
X610103Y-84252D01*
X609963Y-83550D01*
X609565Y-82954D01*
X608970Y-82556D01*
X608268Y-82417D01*
D02*
G37*
G36*
X180610Y-85960D02*
X179908Y-86100D01*
X179413Y-86430D01*
X179085Y-86470D01*
X178756Y-86430D01*
X178261Y-86100D01*
X177559Y-85960D01*
X176857Y-86100D01*
X176261Y-86498D01*
X175864Y-87093D01*
X175724Y-87795D01*
X175864Y-88498D01*
X176261Y-89093D01*
X176857Y-89491D01*
X177559Y-89631D01*
X178261Y-89491D01*
X178756Y-89160D01*
X179085Y-89121D01*
X179413Y-89160D01*
X179908Y-89491D01*
X180610Y-89631D01*
X181313Y-89491D01*
X181908Y-89093D01*
X182306Y-88498D01*
X182446Y-87795D01*
X182306Y-87093D01*
X181908Y-86498D01*
X181313Y-86100D01*
X180610Y-85960D01*
D02*
G37*
G36*
X603543D02*
X602841Y-86100D01*
X602246Y-86498D01*
X601848Y-87093D01*
X601708Y-87795D01*
X601848Y-88498D01*
X602246Y-89093D01*
X602841Y-89491D01*
X603543Y-89631D01*
X604246Y-89491D01*
X604841Y-89093D01*
X605239Y-88498D01*
X605379Y-87795D01*
X605239Y-87093D01*
X604841Y-86498D01*
X604246Y-86100D01*
X603543Y-85960D01*
D02*
G37*
G36*
X198524D02*
X197821Y-86100D01*
X197226Y-86498D01*
X196828Y-87093D01*
X196688Y-87795D01*
X196828Y-88498D01*
X197226Y-89093D01*
X197821Y-89491D01*
X198524Y-89631D01*
X199226Y-89491D01*
X199821Y-89093D01*
X200219Y-88498D01*
X200359Y-87795D01*
X200219Y-87093D01*
X199821Y-86498D01*
X199226Y-86100D01*
X198524Y-85960D01*
D02*
G37*
G36*
X189764Y-86354D02*
X189061Y-86493D01*
X188466Y-86891D01*
X188068Y-87487D01*
X187928Y-88189D01*
X188068Y-88891D01*
X188466Y-89487D01*
X189061Y-89885D01*
X189764Y-90024D01*
X190466Y-89885D01*
X191061Y-89487D01*
X191459Y-88891D01*
X191599Y-88189D01*
X191459Y-87487D01*
X191061Y-86891D01*
X190466Y-86493D01*
X189764Y-86354D01*
D02*
G37*
G36*
X598397Y-86452D02*
X597694Y-86592D01*
X597099Y-86990D01*
X596701Y-87585D01*
X596561Y-88288D01*
X596701Y-88990D01*
X597099Y-89585D01*
X597694Y-89983D01*
X598397Y-90123D01*
X599099Y-89983D01*
X599694Y-89585D01*
X600092Y-88990D01*
X600232Y-88288D01*
X600092Y-87585D01*
X599694Y-86990D01*
X599099Y-86592D01*
X598397Y-86452D01*
D02*
G37*
G36*
X613406Y-87659D02*
X612703Y-87799D01*
X612108Y-88197D01*
X611710Y-88792D01*
X611570Y-89494D01*
X611710Y-90197D01*
X612108Y-90792D01*
X612703Y-91190D01*
X613406Y-91330D01*
X614108Y-91190D01*
X614703Y-90792D01*
X615101Y-90197D01*
X615241Y-89494D01*
X615101Y-88792D01*
X614703Y-88197D01*
X614108Y-87799D01*
X613406Y-87659D01*
D02*
G37*
G36*
X182283Y-95409D02*
X181581Y-95548D01*
X180986Y-95946D01*
X180588Y-96542D01*
X180448Y-97244D01*
X180588Y-97946D01*
X180986Y-98542D01*
X181581Y-98940D01*
X182283Y-99079D01*
X182986Y-98940D01*
X183581Y-98542D01*
X183979Y-97946D01*
X184119Y-97244D01*
X183979Y-96542D01*
X183581Y-95946D01*
X182986Y-95548D01*
X182283Y-95409D01*
D02*
G37*
G36*
X197638Y-95802D02*
X196935Y-95942D01*
X196340Y-96340D01*
X195942Y-96935D01*
X195802Y-97638D01*
X195942Y-98340D01*
X196340Y-98936D01*
X196935Y-99333D01*
X197638Y-99473D01*
X198340Y-99333D01*
X198935Y-98936D01*
X199333Y-98340D01*
X199473Y-97638D01*
X199333Y-96935D01*
X198935Y-96340D01*
X198340Y-95942D01*
X197638Y-95802D01*
D02*
G37*
G36*
X222351Y-96858D02*
X221649Y-96998D01*
X221053Y-97396D01*
X220655Y-97991D01*
X220516Y-98694D01*
X220655Y-99396D01*
X221053Y-99991D01*
X221649Y-100389D01*
X222351Y-100529D01*
X223053Y-100389D01*
X223649Y-99991D01*
X224046Y-99396D01*
X224186Y-98694D01*
X224046Y-97991D01*
X223649Y-97396D01*
X223053Y-96998D01*
X222351Y-96858D01*
D02*
G37*
G36*
X602105Y-97274D02*
X601402Y-97414D01*
X600807Y-97812D01*
X600409Y-98407D01*
X600269Y-99109D01*
X600409Y-99812D01*
X600807Y-100407D01*
X601402Y-100805D01*
X602105Y-100944D01*
X602807Y-100805D01*
X603402Y-100407D01*
X603800Y-99812D01*
X603940Y-99109D01*
X603800Y-98407D01*
X603402Y-97812D01*
X602807Y-97414D01*
X602105Y-97274D01*
D02*
G37*
G36*
X153150Y-97855D02*
X152447Y-97995D01*
X151852Y-98393D01*
X151454Y-98988D01*
X151314Y-99691D01*
X151454Y-100393D01*
X151852Y-100988D01*
X152447Y-101386D01*
X153150Y-101526D01*
X153852Y-101386D01*
X154447Y-100988D01*
X154845Y-100393D01*
X154985Y-99691D01*
X154845Y-98988D01*
X154447Y-98393D01*
X153852Y-97995D01*
X153150Y-97855D01*
D02*
G37*
G36*
X168110Y-98296D02*
X167408Y-98436D01*
X166813Y-98834D01*
X166415Y-99429D01*
X166275Y-100132D01*
X166415Y-100834D01*
X166813Y-101429D01*
X167408Y-101827D01*
X168110Y-101967D01*
X168813Y-101827D01*
X169408Y-101429D01*
X169806Y-100834D01*
X169946Y-100132D01*
X169806Y-99429D01*
X169408Y-98834D01*
X168813Y-98436D01*
X168110Y-98296D01*
D02*
G37*
G36*
X613402Y-94236D02*
X605496D01*
Y-102142D01*
X613402D01*
Y-94236D01*
D02*
G37*
G36*
X619449Y-94202D02*
X618417Y-94338D01*
X617455Y-94736D01*
X616630Y-95370D01*
X615996Y-96196D01*
X615598Y-97157D01*
X615462Y-98189D01*
X615598Y-99221D01*
X615996Y-100182D01*
X616630Y-101008D01*
X617455Y-101642D01*
X618417Y-102040D01*
X619449Y-102176D01*
X620481Y-102040D01*
X621442Y-101642D01*
X622268Y-101008D01*
X622901Y-100182D01*
X623300Y-99221D01*
X623436Y-98189D01*
X623300Y-97157D01*
X622901Y-96196D01*
X622268Y-95370D01*
X621442Y-94736D01*
X620481Y-94338D01*
X619449Y-94202D01*
D02*
G37*
G36*
X181004Y-99346D02*
X180302Y-99485D01*
X179706Y-99883D01*
X179308Y-100479D01*
X179169Y-101181D01*
X179308Y-101883D01*
X179706Y-102479D01*
X180302Y-102877D01*
X181004Y-103016D01*
X181706Y-102877D01*
X182302Y-102479D01*
X182700Y-101883D01*
X182839Y-101181D01*
X182700Y-100479D01*
X182302Y-99883D01*
X181706Y-99485D01*
X181004Y-99346D01*
D02*
G37*
G36*
X204331Y-99739D02*
X203628Y-99879D01*
X203033Y-100277D01*
X202635Y-100873D01*
X202496Y-101575D01*
X202635Y-102277D01*
X203033Y-102873D01*
X203628Y-103270D01*
X204331Y-103410D01*
X205033Y-103270D01*
X205628Y-102873D01*
X206026Y-102277D01*
X206166Y-101575D01*
X206026Y-100873D01*
X205628Y-100277D01*
X205033Y-99879D01*
X204331Y-99739D01*
D02*
G37*
G36*
X418898Y-98165D02*
X418195Y-98304D01*
X417600Y-98702D01*
X417202Y-99298D01*
X417062Y-100000D01*
X417202Y-100702D01*
X417600Y-101298D01*
X418195Y-101696D01*
X418898Y-101835D01*
X419600Y-101696D01*
X419780Y-101575D01*
X420230Y-101876D01*
X420212Y-101969D01*
X420352Y-102671D01*
X420750Y-103266D01*
X421345Y-103664D01*
X422047Y-103804D01*
X422750Y-103664D01*
X423345Y-103266D01*
X423743Y-102671D01*
X423882Y-101969D01*
X423743Y-101266D01*
X423345Y-100671D01*
X422750Y-100273D01*
X422047Y-100133D01*
X421345Y-100273D01*
X421164Y-100394D01*
X420714Y-100093D01*
X420733Y-100000D01*
X420593Y-99298D01*
X420195Y-98702D01*
X419600Y-98304D01*
X418898Y-98165D01*
D02*
G37*
G36*
X582058Y-81850D02*
X580331Y-81986D01*
X578648Y-82390D01*
X577048Y-83052D01*
X575572Y-83957D01*
X574255Y-85082D01*
X573131Y-86398D01*
X572226Y-87875D01*
X571564Y-89474D01*
X571159Y-91158D01*
X571024Y-92884D01*
X571159Y-94610D01*
X571564Y-96293D01*
X572226Y-97893D01*
X573131Y-99370D01*
X574255Y-100686D01*
X575572Y-101811D01*
X577048Y-102715D01*
X578648Y-103378D01*
X580331Y-103782D01*
X582058Y-103918D01*
X583784Y-103782D01*
X585467Y-103378D01*
X587067Y-102715D01*
X588543Y-101811D01*
X589860Y-100686D01*
X590984Y-99370D01*
X591889Y-97893D01*
X592552Y-96293D01*
X592956Y-94610D01*
X593091Y-92884D01*
X592956Y-91158D01*
X592552Y-89474D01*
X591889Y-87875D01*
X590984Y-86398D01*
X589860Y-85082D01*
X588543Y-83957D01*
X587067Y-83052D01*
X585467Y-82390D01*
X583784Y-81986D01*
X582058Y-81850D01*
D02*
G37*
G36*
X479695D02*
X477969Y-81986D01*
X476286Y-82390D01*
X474686Y-83052D01*
X473210Y-83957D01*
X471893Y-85082D01*
X470769Y-86398D01*
X469864Y-87875D01*
X469201Y-89474D01*
X468797Y-91158D01*
X468661Y-92884D01*
X468797Y-94610D01*
X469201Y-96293D01*
X469864Y-97893D01*
X470769Y-99370D01*
X471893Y-100686D01*
X473210Y-101811D01*
X474686Y-102715D01*
X476286Y-103378D01*
X477969Y-103782D01*
X479695Y-103918D01*
X481421Y-103782D01*
X483105Y-103378D01*
X484705Y-102715D01*
X486181Y-101811D01*
X487498Y-100686D01*
X488622Y-99370D01*
X489527Y-97893D01*
X490189Y-96293D01*
X490593Y-94610D01*
X490729Y-92884D01*
X490593Y-91158D01*
X490189Y-89474D01*
X489527Y-87875D01*
X488622Y-86398D01*
X487498Y-85082D01*
X486181Y-83957D01*
X484705Y-83052D01*
X483105Y-82390D01*
X481421Y-81986D01*
X479695Y-81850D01*
D02*
G37*
G36*
X211648Y-101859D02*
X210946Y-101999D01*
X210350Y-102397D01*
X209953Y-102992D01*
X209813Y-103695D01*
X209953Y-104397D01*
X210350Y-104992D01*
X210946Y-105390D01*
X211648Y-105530D01*
X212351Y-105390D01*
X212946Y-104992D01*
X213344Y-104397D01*
X213484Y-103695D01*
X213344Y-102992D01*
X212946Y-102397D01*
X212351Y-101999D01*
X211648Y-101859D01*
D02*
G37*
G36*
X365581Y-83523D02*
X363855Y-83659D01*
X362171Y-84063D01*
X360571Y-84725D01*
X359095Y-85630D01*
X357779Y-86755D01*
X356654Y-88071D01*
X355749Y-89547D01*
X355087Y-91147D01*
X354683Y-92831D01*
X354547Y-94557D01*
X354683Y-96283D01*
X355087Y-97966D01*
X355749Y-99566D01*
X356654Y-101042D01*
X357779Y-102359D01*
X359095Y-103483D01*
X360571Y-104388D01*
X362171Y-105051D01*
X363855Y-105455D01*
X365581Y-105591D01*
X367307Y-105455D01*
X368990Y-105051D01*
X370590Y-104388D01*
X372066Y-103483D01*
X373383Y-102359D01*
X374507Y-101042D01*
X375412Y-99566D01*
X376075Y-97966D01*
X376479Y-96283D01*
X376615Y-94557D01*
X376479Y-92831D01*
X376075Y-91147D01*
X375412Y-89547D01*
X374507Y-88071D01*
X373383Y-86755D01*
X372066Y-85630D01*
X370590Y-84725D01*
X368990Y-84063D01*
X367307Y-83659D01*
X365581Y-83523D01*
D02*
G37*
G36*
X127392D02*
X125666Y-83659D01*
X123982Y-84063D01*
X122382Y-84725D01*
X120906Y-85630D01*
X119589Y-86755D01*
X118465Y-88071D01*
X117560Y-89547D01*
X116898Y-91147D01*
X116494Y-92831D01*
X116358Y-94557D01*
X116494Y-96283D01*
X116898Y-97966D01*
X117560Y-99566D01*
X118465Y-101042D01*
X119589Y-102359D01*
X120906Y-103483D01*
X122382Y-104388D01*
X123982Y-105051D01*
X125666Y-105455D01*
X127392Y-105591D01*
X129118Y-105455D01*
X130801Y-105051D01*
X132401Y-104388D01*
X133877Y-103483D01*
X135194Y-102359D01*
X136319Y-101042D01*
X137223Y-99566D01*
X137886Y-97966D01*
X138290Y-96283D01*
X138426Y-94557D01*
X138290Y-92831D01*
X137886Y-91147D01*
X137223Y-89547D01*
X136319Y-88071D01*
X135194Y-86755D01*
X133877Y-85630D01*
X132401Y-84725D01*
X130801Y-84063D01*
X129118Y-83659D01*
X127392Y-83523D01*
D02*
G37*
G36*
X197244Y-100921D02*
X196542Y-101060D01*
X195946Y-101458D01*
X195548Y-102054D01*
X195409Y-102756D01*
X195548Y-103458D01*
X195946Y-104054D01*
X196542Y-104452D01*
X197244Y-104591D01*
X197329Y-104574D01*
X197630Y-105024D01*
X197497Y-105223D01*
X197358Y-105925D01*
X197497Y-106627D01*
X197895Y-107223D01*
X198491Y-107621D01*
X199193Y-107760D01*
X199895Y-107621D01*
X200491Y-107223D01*
X200888Y-106627D01*
X201028Y-105925D01*
X200888Y-105223D01*
X200491Y-104627D01*
X199895Y-104229D01*
X199193Y-104090D01*
X199108Y-104107D01*
X198807Y-103657D01*
X198940Y-103458D01*
X199079Y-102756D01*
X198940Y-102054D01*
X198542Y-101458D01*
X197946Y-101060D01*
X197244Y-100921D01*
D02*
G37*
G36*
X238189Y-105251D02*
X237487Y-105391D01*
X236891Y-105789D01*
X236493Y-106384D01*
X236354Y-107087D01*
X236493Y-107789D01*
X236891Y-108384D01*
X237487Y-108782D01*
X238189Y-108922D01*
X238891Y-108782D01*
X239487Y-108384D01*
X239884Y-107789D01*
X240024Y-107087D01*
X239884Y-106384D01*
X239487Y-105789D01*
X238891Y-105391D01*
X238189Y-105251D01*
D02*
G37*
G36*
X233071D02*
X232369Y-105391D01*
X231773Y-105789D01*
X231375Y-106384D01*
X231236Y-107087D01*
X231375Y-107789D01*
X231773Y-108384D01*
X232369Y-108782D01*
X233071Y-108922D01*
X233773Y-108782D01*
X234369Y-108384D01*
X234766Y-107789D01*
X234906Y-107087D01*
X234766Y-106384D01*
X234369Y-105789D01*
X233773Y-105391D01*
X233071Y-105251D01*
D02*
G37*
G36*
X228346Y-105645D02*
X227644Y-105785D01*
X227049Y-106183D01*
X226651Y-106778D01*
X226511Y-107480D01*
X226651Y-108183D01*
X227049Y-108778D01*
X227644Y-109176D01*
X228346Y-109316D01*
X229049Y-109176D01*
X229644Y-108778D01*
X230042Y-108183D01*
X230182Y-107480D01*
X230042Y-106778D01*
X229644Y-106183D01*
X229049Y-105785D01*
X228346Y-105645D01*
D02*
G37*
G36*
X223228D02*
X222526Y-105785D01*
X221931Y-106183D01*
X221533Y-106778D01*
X221393Y-107480D01*
X221533Y-108183D01*
X221931Y-108778D01*
X222526Y-109176D01*
X223228Y-109316D01*
X223931Y-109176D01*
X224526Y-108778D01*
X224924Y-108183D01*
X225064Y-107480D01*
X224924Y-106778D01*
X224526Y-106183D01*
X223931Y-105785D01*
X223228Y-105645D01*
D02*
G37*
G36*
X88981Y-106226D02*
X88279Y-106366D01*
X87684Y-106763D01*
X87286Y-107359D01*
X87212Y-107730D01*
X87022Y-108112D01*
X86675Y-108255D01*
X86279Y-108334D01*
X85684Y-108732D01*
X85286Y-109327D01*
X85205Y-109735D01*
X84695D01*
X84614Y-109327D01*
X84216Y-108732D01*
X83621Y-108334D01*
X83251Y-108261D01*
X82817Y-108061D01*
X82677Y-107359D01*
X82279Y-106763D01*
X81684Y-106366D01*
X80981Y-106226D01*
X80279Y-106366D01*
X79684Y-106763D01*
X79286Y-107359D01*
X79210Y-107742D01*
X78918Y-108194D01*
X78216Y-108334D01*
X77621Y-108732D01*
X77223Y-109327D01*
X77083Y-110029D01*
X77223Y-110732D01*
X77621Y-111327D01*
X78216Y-111725D01*
X78918Y-111865D01*
X79621Y-111725D01*
X80216Y-111327D01*
X80614Y-110732D01*
X80664Y-110483D01*
X81173D01*
X81223Y-110732D01*
X81621Y-111327D01*
X82216Y-111725D01*
X82918Y-111865D01*
X83621Y-111725D01*
X84216Y-111327D01*
X84614Y-110732D01*
X84695Y-110325D01*
X85205D01*
X85286Y-110732D01*
X85684Y-111327D01*
X86279Y-111725D01*
X86981Y-111865D01*
X87684Y-111725D01*
X88279Y-111327D01*
X88677Y-110732D01*
X88755Y-110340D01*
X89265D01*
X89349Y-110763D01*
X89747Y-111359D01*
X90342Y-111757D01*
X91044Y-111896D01*
X91747Y-111757D01*
X92342Y-111359D01*
X92740Y-110763D01*
X92880Y-110061D01*
X92740Y-109359D01*
X92342Y-108763D01*
X91747Y-108365D01*
X91284Y-108273D01*
X90817Y-108061D01*
X90677Y-107359D01*
X90279Y-106763D01*
X89684Y-106366D01*
X88981Y-106226D01*
D02*
G37*
G36*
X597244Y-106826D02*
X596542Y-106966D01*
X595946Y-107364D01*
X595548Y-107959D01*
X595409Y-108661D01*
X595548Y-109364D01*
X595946Y-109959D01*
X596542Y-110357D01*
X597244Y-110497D01*
X597946Y-110357D01*
X598542Y-109959D01*
X598940Y-109364D01*
X599079Y-108661D01*
X598940Y-107959D01*
X598542Y-107364D01*
X597946Y-106966D01*
X597244Y-106826D01*
D02*
G37*
G36*
X-23622Y-100527D02*
X-24324Y-100667D01*
X-24920Y-101065D01*
X-25318Y-101660D01*
X-25457Y-102362D01*
X-25318Y-103065D01*
X-24920Y-103660D01*
X-24324Y-104058D01*
X-24234Y-104076D01*
Y-104586D01*
X-24324Y-104604D01*
X-24920Y-105001D01*
X-25318Y-105597D01*
X-25457Y-106299D01*
X-25318Y-107001D01*
X-24920Y-107597D01*
X-24324Y-107995D01*
X-24234Y-108013D01*
Y-108523D01*
X-24324Y-108541D01*
X-24920Y-108939D01*
X-25318Y-109534D01*
X-25457Y-110236D01*
X-25318Y-110939D01*
X-24920Y-111534D01*
X-24324Y-111932D01*
X-23622Y-112072D01*
X-22920Y-111932D01*
X-22324Y-111534D01*
X-21926Y-110939D01*
X-21787Y-110236D01*
X-21926Y-109534D01*
X-22324Y-108939D01*
X-22920Y-108541D01*
X-23010Y-108523D01*
Y-108013D01*
X-22920Y-107995D01*
X-22324Y-107597D01*
X-21926Y-107001D01*
X-21787Y-106299D01*
X-21926Y-105597D01*
X-22324Y-105001D01*
X-22920Y-104604D01*
X-23010Y-104586D01*
Y-104076D01*
X-22920Y-104058D01*
X-22324Y-103660D01*
X-21926Y-103065D01*
X-21787Y-102362D01*
X-21926Y-101660D01*
X-22324Y-101065D01*
X-22920Y-100667D01*
X-23622Y-100527D01*
D02*
G37*
G36*
X619449Y-104202D02*
X618417Y-104338D01*
X617455Y-104736D01*
X616630Y-105370D01*
X615996Y-106196D01*
X615598Y-107157D01*
X615462Y-108189D01*
X615598Y-109221D01*
X615996Y-110182D01*
X616630Y-111008D01*
X617455Y-111642D01*
X618417Y-112040D01*
X619449Y-112176D01*
X620481Y-112040D01*
X621442Y-111642D01*
X622268Y-111008D01*
X622901Y-110182D01*
X623300Y-109221D01*
X623436Y-108189D01*
X623300Y-107157D01*
X622901Y-106196D01*
X622268Y-105370D01*
X621442Y-104736D01*
X620481Y-104338D01*
X619449Y-104202D01*
D02*
G37*
G36*
X609449D02*
X608417Y-104338D01*
X607455Y-104736D01*
X606630Y-105370D01*
X605996Y-106196D01*
X605598Y-107157D01*
X605462Y-108189D01*
X605598Y-109221D01*
X605996Y-110182D01*
X606630Y-111008D01*
X607455Y-111642D01*
X608417Y-112040D01*
X609449Y-112176D01*
X610481Y-112040D01*
X611442Y-111642D01*
X612268Y-111008D01*
X612901Y-110182D01*
X613300Y-109221D01*
X613436Y-108189D01*
X613300Y-107157D01*
X612901Y-106196D01*
X612268Y-105370D01*
X611442Y-104736D01*
X610481Y-104338D01*
X609449Y-104202D01*
D02*
G37*
G36*
X44621Y-108792D02*
X43919Y-108932D01*
X43324Y-109330D01*
X42926Y-109925D01*
X42786Y-110628D01*
X42926Y-111330D01*
X43324Y-111925D01*
X43919Y-112323D01*
X44621Y-112463D01*
X45324Y-112323D01*
X45919Y-111925D01*
X46317Y-111330D01*
X46457Y-110628D01*
X46317Y-109925D01*
X45919Y-109330D01*
X45324Y-108932D01*
X44621Y-108792D01*
D02*
G37*
G36*
X160075Y-110566D02*
X159373Y-110706D01*
X158778Y-111104D01*
X158380Y-111699D01*
X158240Y-112402D01*
X158380Y-113104D01*
X158778Y-113699D01*
X159373Y-114097D01*
X160075Y-114237D01*
X160778Y-114097D01*
X161373Y-113699D01*
X161771Y-113104D01*
X161910Y-112402D01*
X161771Y-111699D01*
X161373Y-111104D01*
X160778Y-110706D01*
X160075Y-110566D01*
D02*
G37*
G36*
X321260Y-113125D02*
X320557Y-113265D01*
X319962Y-113663D01*
X319564Y-114258D01*
X319546Y-114349D01*
X319036D01*
X319018Y-114258D01*
X318621Y-113663D01*
X318025Y-113265D01*
X317323Y-113125D01*
X316620Y-113265D01*
X316025Y-113663D01*
X315627Y-114258D01*
X315488Y-114961D01*
X315627Y-115663D01*
X316025Y-116258D01*
X316620Y-116656D01*
X317323Y-116796D01*
X318025Y-116656D01*
X318621Y-116258D01*
X319018Y-115663D01*
X319036Y-115572D01*
X319546D01*
X319564Y-115663D01*
X319962Y-116258D01*
X320557Y-116656D01*
X321260Y-116796D01*
X321962Y-116656D01*
X322558Y-116258D01*
X322955Y-115663D01*
X323095Y-114961D01*
X322955Y-114258D01*
X322558Y-113663D01*
X321962Y-113265D01*
X321260Y-113125D01*
D02*
G37*
G36*
X153150Y-111551D02*
X152447Y-111690D01*
X151852Y-112088D01*
X151454Y-112683D01*
X151314Y-113386D01*
X151454Y-114088D01*
X151852Y-114683D01*
X152447Y-115081D01*
X153150Y-115221D01*
X153852Y-115081D01*
X154447Y-114683D01*
X154845Y-114088D01*
X154985Y-113386D01*
X154845Y-112683D01*
X154447Y-112088D01*
X153852Y-111690D01*
X153150Y-111551D01*
D02*
G37*
G36*
X188028Y-111747D02*
X187326Y-111887D01*
X186730Y-112285D01*
X186332Y-112880D01*
X186193Y-113583D01*
X186332Y-114285D01*
X186730Y-114880D01*
X187326Y-115278D01*
X188028Y-115418D01*
X188730Y-115278D01*
X189326Y-114880D01*
X189724Y-114285D01*
X189863Y-113583D01*
X189724Y-112880D01*
X189326Y-112285D01*
X188730Y-111887D01*
X188028Y-111747D01*
D02*
G37*
G36*
X164843Y-112204D02*
X164140Y-112344D01*
X163545Y-112742D01*
X163147Y-113337D01*
X163008Y-114040D01*
X163147Y-114742D01*
X163545Y-115337D01*
X164140Y-115735D01*
X164843Y-115875D01*
X165545Y-115735D01*
X166141Y-115337D01*
X166538Y-114742D01*
X166678Y-114040D01*
X166538Y-113337D01*
X166141Y-112742D01*
X165545Y-112344D01*
X164843Y-112204D01*
D02*
G37*
G36*
X369685Y-116275D02*
X368983Y-116415D01*
X368692Y-116609D01*
X368307Y-116777D01*
X367922Y-116609D01*
X367631Y-116415D01*
X366929Y-116275D01*
X366227Y-116415D01*
X365664Y-116791D01*
X365517Y-116853D01*
X365191D01*
X365045Y-116791D01*
X364482Y-116415D01*
X363779Y-116275D01*
X363077Y-116415D01*
X362482Y-116813D01*
X362084Y-117408D01*
X361944Y-118110D01*
X362084Y-118813D01*
X362278Y-119103D01*
X362447Y-119488D01*
X362278Y-119873D01*
X362084Y-120164D01*
X361944Y-120866D01*
X362084Y-121569D01*
X362482Y-122164D01*
Y-122324D01*
X362084Y-122920D01*
X361944Y-123622D01*
X362084Y-124324D01*
X362482Y-124920D01*
X363077Y-125318D01*
X363779Y-125457D01*
X364482Y-125318D01*
X365045Y-124942D01*
X365191Y-124879D01*
X365517D01*
X365664Y-124942D01*
X366227Y-125318D01*
X366929Y-125457D01*
X367631Y-125318D01*
X367922Y-125123D01*
X368307Y-124955D01*
X368692Y-125123D01*
X368983Y-125318D01*
X369685Y-125457D01*
X370387Y-125318D01*
X370983Y-124920D01*
X371381Y-124324D01*
X371520Y-123622D01*
X371381Y-122920D01*
X370983Y-122324D01*
Y-122164D01*
X371381Y-121569D01*
X371520Y-120866D01*
X371381Y-120164D01*
X371186Y-119873D01*
X371018Y-119488D01*
X371186Y-119103D01*
X371381Y-118813D01*
X371520Y-118110D01*
X371381Y-117408D01*
X370983Y-116813D01*
X370387Y-116415D01*
X369685Y-116275D01*
D02*
G37*
G36*
X245276Y-113913D02*
X244573Y-114052D01*
X243978Y-114450D01*
X243580Y-115046D01*
X243440Y-115748D01*
X243580Y-116450D01*
X243978Y-117046D01*
X244573Y-117444D01*
X245276Y-117583D01*
X245978Y-117444D01*
X246573Y-117046D01*
X246971Y-116450D01*
X247111Y-115748D01*
X246971Y-115046D01*
X246573Y-114450D01*
X245978Y-114052D01*
X245276Y-113913D01*
D02*
G37*
G36*
X592913Y-114700D02*
X592211Y-114840D01*
X591616Y-115238D01*
X591218Y-115833D01*
X591078Y-116535D01*
X591218Y-117238D01*
X591616Y-117833D01*
X592211Y-118231D01*
X592913Y-118371D01*
X593616Y-118231D01*
X594211Y-117833D01*
X594609Y-117238D01*
X594749Y-116535D01*
X594609Y-115833D01*
X594211Y-115238D01*
X593616Y-114840D01*
X592913Y-114700D01*
D02*
G37*
G36*
X173228Y-115488D02*
X172526Y-115627D01*
X171931Y-116025D01*
X171533Y-116621D01*
X171393Y-117323D01*
X171533Y-118025D01*
X171931Y-118621D01*
X172526Y-119018D01*
X173228Y-119158D01*
X173931Y-119018D01*
X174526Y-118621D01*
X174924Y-118025D01*
X175064Y-117323D01*
X174924Y-116621D01*
X174526Y-116025D01*
X173931Y-115627D01*
X173228Y-115488D01*
D02*
G37*
G36*
X298031Y-111426D02*
X296974Y-111565D01*
X295988Y-111973D01*
X295142Y-112622D01*
X294493Y-113469D01*
X294085Y-114454D01*
X293945Y-115512D01*
X294085Y-116569D01*
X294493Y-117555D01*
X295142Y-118401D01*
X295988Y-119051D01*
X296974Y-119459D01*
X298031Y-119598D01*
X299089Y-119459D01*
X300075Y-119051D01*
X300921Y-118401D01*
X301570Y-117555D01*
X301978Y-116569D01*
X302118Y-115512D01*
X301978Y-114454D01*
X301570Y-113469D01*
X300921Y-112622D01*
X300075Y-111973D01*
X299089Y-111565D01*
X298031Y-111426D01*
D02*
G37*
G36*
X140551Y-114700D02*
X139849Y-114840D01*
X139253Y-115238D01*
X138856Y-115833D01*
X138716Y-116535D01*
X138842Y-117167D01*
X138668Y-117202D01*
X138072Y-117600D01*
X137674Y-118195D01*
X137535Y-118898D01*
X137674Y-119600D01*
X138072Y-120195D01*
X138668Y-120593D01*
X139370Y-120733D01*
X140072Y-120593D01*
X140668Y-120195D01*
X141066Y-119600D01*
X141205Y-118898D01*
X141080Y-118266D01*
X141253Y-118231D01*
X141849Y-117833D01*
X142247Y-117238D01*
X142386Y-116535D01*
X142247Y-115833D01*
X141849Y-115238D01*
X141253Y-114840D01*
X140551Y-114700D01*
D02*
G37*
G36*
X52501Y-118037D02*
X51799Y-118176D01*
X51203Y-118574D01*
X50805Y-119170D01*
X50666Y-119872D01*
X50805Y-120574D01*
X51203Y-121170D01*
X51799Y-121568D01*
X52501Y-121707D01*
X53203Y-121568D01*
X53799Y-121170D01*
X54197Y-120574D01*
X54336Y-119872D01*
X54197Y-119170D01*
X53799Y-118574D01*
X53203Y-118176D01*
X52501Y-118037D01*
D02*
G37*
G36*
X619449Y-114202D02*
X618417Y-114338D01*
X617455Y-114736D01*
X616630Y-115370D01*
X615996Y-116196D01*
X615598Y-117157D01*
X615462Y-118189D01*
X615598Y-119221D01*
X615996Y-120182D01*
X616630Y-121008D01*
X617455Y-121642D01*
X618417Y-122040D01*
X619449Y-122176D01*
X620481Y-122040D01*
X621442Y-121642D01*
X622268Y-121008D01*
X622901Y-120182D01*
X623300Y-119221D01*
X623436Y-118189D01*
X623300Y-117157D01*
X622901Y-116196D01*
X622268Y-115370D01*
X621442Y-114736D01*
X620481Y-114338D01*
X619449Y-114202D01*
D02*
G37*
G36*
X609449D02*
X608417Y-114338D01*
X607455Y-114736D01*
X606630Y-115370D01*
X605996Y-116196D01*
X605598Y-117157D01*
X605462Y-118189D01*
X605598Y-119221D01*
X605996Y-120182D01*
X606630Y-121008D01*
X607455Y-121642D01*
X608417Y-122040D01*
X609449Y-122176D01*
X610481Y-122040D01*
X611442Y-121642D01*
X612268Y-121008D01*
X612901Y-120182D01*
X613300Y-119221D01*
X613436Y-118189D01*
X613300Y-117157D01*
X612901Y-116196D01*
X612268Y-115370D01*
X611442Y-114736D01*
X610481Y-114338D01*
X609449Y-114202D01*
D02*
G37*
G36*
X245325Y-119002D02*
X244623Y-119141D01*
X244027Y-119539D01*
X243629Y-120135D01*
X243490Y-120837D01*
X243629Y-121539D01*
X244027Y-122135D01*
X244623Y-122532D01*
X245325Y-122672D01*
X246027Y-122532D01*
X246623Y-122135D01*
X247020Y-121539D01*
X247160Y-120837D01*
X247020Y-120135D01*
X246623Y-119539D01*
X246027Y-119141D01*
X245325Y-119002D01*
D02*
G37*
G36*
X130245Y-119034D02*
X129542Y-119174D01*
X128947Y-119572D01*
X128549Y-120167D01*
X128409Y-120870D01*
X128549Y-121572D01*
X128947Y-122167D01*
X129542Y-122565D01*
X130245Y-122705D01*
X130947Y-122565D01*
X131542Y-122167D01*
X131940Y-121572D01*
X132080Y-120870D01*
X131940Y-120167D01*
X131542Y-119572D01*
X130947Y-119174D01*
X130245Y-119034D01*
D02*
G37*
G36*
X140116Y-122213D02*
X139414Y-122353D01*
X138818Y-122751D01*
X138421Y-123346D01*
X138281Y-124048D01*
X138421Y-124751D01*
X138818Y-125346D01*
X139414Y-125744D01*
X140116Y-125884D01*
X140819Y-125744D01*
X141414Y-125346D01*
X141812Y-124751D01*
X141951Y-124048D01*
X141812Y-123346D01*
X141414Y-122751D01*
X140819Y-122353D01*
X140116Y-122213D01*
D02*
G37*
G36*
X150233Y-118047D02*
X149530Y-118186D01*
X148935Y-118584D01*
X148537Y-119180D01*
X148398Y-119882D01*
X148537Y-120584D01*
X148935Y-121180D01*
X149530Y-121577D01*
X150233Y-121717D01*
X150935Y-121577D01*
X150956Y-121564D01*
X151413Y-121860D01*
X151530Y-122449D01*
X151769Y-122807D01*
X151607Y-122915D01*
X151209Y-123510D01*
X151069Y-124213D01*
X151209Y-124915D01*
X151607Y-125510D01*
X152202Y-125908D01*
X152904Y-126048D01*
X153607Y-125908D01*
X154202Y-125510D01*
X154600Y-124915D01*
X154739Y-124213D01*
X154600Y-123510D01*
X154361Y-123153D01*
X154523Y-123044D01*
X154921Y-122449D01*
X155061Y-121747D01*
X154921Y-121044D01*
X154523Y-120449D01*
X153928Y-120051D01*
X153225Y-119911D01*
X152523Y-120051D01*
X152503Y-120065D01*
X152046Y-119769D01*
X151928Y-119180D01*
X151531Y-118584D01*
X150935Y-118186D01*
X150233Y-118047D01*
D02*
G37*
G36*
X281496Y-122574D02*
X280794Y-122714D01*
X280198Y-123112D01*
X279801Y-123707D01*
X279661Y-124409D01*
X279801Y-125112D01*
X280198Y-125707D01*
X280794Y-126105D01*
X281496Y-126245D01*
X282198Y-126105D01*
X282794Y-125707D01*
X283192Y-125112D01*
X283331Y-124409D01*
X283192Y-123707D01*
X282794Y-123112D01*
X282198Y-122714D01*
X281496Y-122574D01*
D02*
G37*
G36*
X449606Y-119818D02*
X448904Y-119958D01*
X448309Y-120356D01*
X447911Y-120951D01*
X447771Y-121653D01*
X447911Y-122356D01*
X448309Y-122951D01*
X448349Y-122978D01*
Y-123478D01*
X448309Y-123505D01*
X447911Y-124101D01*
X447771Y-124803D01*
X447911Y-125505D01*
X448309Y-126101D01*
X448568Y-126274D01*
Y-126875D01*
X448309Y-127049D01*
X447911Y-127644D01*
X447893Y-127735D01*
X447383D01*
X447365Y-127644D01*
X446967Y-127049D01*
X446372Y-126651D01*
X445669Y-126511D01*
X444967Y-126651D01*
X444372Y-127049D01*
X443974Y-127644D01*
X443834Y-128347D01*
X443974Y-129049D01*
X444372Y-129644D01*
X444967Y-130042D01*
X445669Y-130182D01*
X446372Y-130042D01*
X446967Y-129644D01*
X447365Y-129049D01*
X447383Y-128958D01*
X447893D01*
X447911Y-129049D01*
X448309Y-129644D01*
X448904Y-130042D01*
X449606Y-130182D01*
X450309Y-130042D01*
X450904Y-129644D01*
X451302Y-129049D01*
X451442Y-128347D01*
X451302Y-127644D01*
X450904Y-127049D01*
X450645Y-126875D01*
Y-126274D01*
X450904Y-126101D01*
X451302Y-125505D01*
X451442Y-124803D01*
X451302Y-124101D01*
X450904Y-123505D01*
X450864Y-123478D01*
Y-122978D01*
X450904Y-122951D01*
X451302Y-122356D01*
X451442Y-121653D01*
X451302Y-120951D01*
X450904Y-120356D01*
X450309Y-119958D01*
X449606Y-119818D01*
D02*
G37*
G36*
X255906Y-124543D02*
X255203Y-124682D01*
X254608Y-125080D01*
X254210Y-125676D01*
X254070Y-126378D01*
X254210Y-127080D01*
X254608Y-127676D01*
X255203Y-128074D01*
X255906Y-128213D01*
X256608Y-128074D01*
X257203Y-127676D01*
X257601Y-127080D01*
X257741Y-126378D01*
X257601Y-125676D01*
X257203Y-125080D01*
X256608Y-124682D01*
X255906Y-124543D01*
D02*
G37*
G36*
X35433Y-127692D02*
X34731Y-127832D01*
X34135Y-128230D01*
X34108Y-128270D01*
X33608D01*
X33581Y-128230D01*
X32986Y-127832D01*
X32283Y-127692D01*
X31581Y-127832D01*
X30986Y-128230D01*
X30812Y-128489D01*
X30211D01*
X30038Y-128230D01*
X29443Y-127832D01*
X28740Y-127692D01*
X28038Y-127832D01*
X27442Y-128230D01*
X27045Y-128825D01*
X26905Y-129528D01*
X27045Y-130230D01*
X27442Y-130825D01*
X28038Y-131223D01*
X28740Y-131363D01*
X29443Y-131223D01*
X30038Y-130825D01*
X30211Y-130566D01*
X30812D01*
X30986Y-130825D01*
X31581Y-131223D01*
X32283Y-131363D01*
X32986Y-131223D01*
X33581Y-130825D01*
X33608Y-130785D01*
X34108D01*
X34135Y-130825D01*
X34731Y-131223D01*
X35433Y-131363D01*
X36135Y-131223D01*
X36731Y-130825D01*
X37129Y-130230D01*
X37268Y-129528D01*
X37129Y-128825D01*
X36731Y-128230D01*
X36135Y-127832D01*
X35433Y-127692D01*
D02*
G37*
G36*
X51287Y-125042D02*
X50585Y-125182D01*
X49989Y-125580D01*
X49591Y-126175D01*
X49452Y-126878D01*
X49591Y-127580D01*
X49989Y-128175D01*
X50585Y-128573D01*
X51287Y-128713D01*
X51989Y-128573D01*
X52585Y-128175D01*
X52983Y-127580D01*
X53122Y-126878D01*
X52983Y-126175D01*
X52585Y-125580D01*
X51989Y-125182D01*
X51287Y-125042D01*
D02*
G37*
G36*
X13386D02*
X12684Y-125182D01*
X12088Y-125580D01*
X11690Y-126175D01*
X11551Y-126878D01*
X11690Y-127580D01*
X12088Y-128175D01*
X12684Y-128573D01*
X13386Y-128713D01*
X14088Y-128573D01*
X14683Y-128175D01*
X15081Y-127580D01*
X15221Y-126878D01*
X15081Y-126175D01*
X14683Y-125580D01*
X14088Y-125182D01*
X13386Y-125042D01*
D02*
G37*
G36*
X400984Y-125267D02*
X400282Y-125406D01*
X399687Y-125804D01*
X399289Y-126400D01*
X399149Y-127102D01*
X399289Y-127804D01*
X399687Y-128400D01*
X400282Y-128798D01*
X400984Y-128937D01*
X401687Y-128798D01*
X402282Y-128400D01*
X402680Y-127804D01*
X402819Y-127102D01*
X402680Y-126400D01*
X402282Y-125804D01*
X401687Y-125406D01*
X400984Y-125267D01*
D02*
G37*
G36*
X298031Y-121426D02*
X296974Y-121565D01*
X295988Y-121973D01*
X295142Y-122623D01*
X294493Y-123469D01*
X294085Y-124454D01*
X293945Y-125512D01*
X294085Y-126569D01*
X294493Y-127555D01*
X295142Y-128401D01*
X295988Y-129051D01*
X296974Y-129459D01*
X298031Y-129598D01*
X299089Y-129459D01*
X300075Y-129051D01*
X300921Y-128401D01*
X301570Y-127555D01*
X301978Y-126569D01*
X302118Y-125512D01*
X301978Y-124454D01*
X301570Y-123469D01*
X300921Y-122623D01*
X300075Y-121973D01*
X299089Y-121565D01*
X298031Y-121426D01*
D02*
G37*
G36*
X321260Y-121484D02*
X320177Y-121626D01*
X319167Y-122045D01*
X318300Y-122710D01*
X317635Y-123577D01*
X317217Y-124586D01*
X317074Y-125669D01*
X317217Y-126752D01*
X317635Y-127762D01*
X318300Y-128629D01*
X319167Y-129294D01*
X320177Y-129712D01*
X321260Y-129855D01*
X322343Y-129712D01*
X323353Y-129294D01*
X324219Y-128629D01*
X324885Y-127762D01*
X325303Y-126752D01*
X325445Y-125669D01*
X325303Y-124586D01*
X324885Y-123577D01*
X324219Y-122710D01*
X323353Y-122045D01*
X322343Y-121626D01*
X321260Y-121484D01*
D02*
G37*
G36*
X286221Y-122968D02*
X285518Y-123108D01*
X284923Y-123505D01*
X284525Y-124101D01*
X284385Y-124803D01*
X284525Y-125505D01*
X284889Y-126050D01*
X284824Y-126245D01*
X284642Y-126512D01*
X283943Y-126651D01*
X283348Y-127049D01*
X282950Y-127644D01*
X282810Y-128347D01*
X282950Y-129049D01*
X283348Y-129644D01*
X283943Y-130042D01*
X284646Y-130182D01*
X285348Y-130042D01*
X285943Y-129644D01*
X286341Y-129049D01*
X286481Y-128347D01*
X286341Y-127644D01*
X285978Y-127100D01*
X286042Y-126904D01*
X286224Y-126638D01*
X286923Y-126499D01*
X287518Y-126101D01*
X287916Y-125505D01*
X288056Y-124803D01*
X287916Y-124101D01*
X287518Y-123505D01*
X286923Y-123108D01*
X286221Y-122968D01*
D02*
G37*
G36*
X388713Y-126896D02*
X388010Y-127036D01*
X387415Y-127433D01*
X387017Y-128029D01*
X386877Y-128731D01*
X387017Y-129433D01*
X387415Y-130029D01*
X388010Y-130427D01*
X388713Y-130566D01*
X389415Y-130427D01*
X390010Y-130029D01*
X390408Y-129433D01*
X390548Y-128731D01*
X390408Y-128029D01*
X390010Y-127433D01*
X389415Y-127036D01*
X388713Y-126896D01*
D02*
G37*
G36*
X276650Y-126975D02*
X275948Y-127115D01*
X275352Y-127513D01*
X274954Y-128108D01*
X274815Y-128810D01*
X274954Y-129513D01*
X275352Y-130108D01*
X275948Y-130506D01*
X276650Y-130646D01*
X277352Y-130506D01*
X277948Y-130108D01*
X278346Y-129513D01*
X278485Y-128810D01*
X278346Y-128108D01*
X277948Y-127513D01*
X277352Y-127115D01*
X276650Y-126975D01*
D02*
G37*
G36*
X415748Y-127774D02*
X415046Y-127913D01*
X414450Y-128311D01*
X414052Y-128907D01*
X413913Y-129609D01*
X414052Y-130311D01*
X414450Y-130907D01*
X415046Y-131304D01*
X415748Y-131444D01*
X416450Y-131304D01*
X417046Y-130907D01*
X417503D01*
X417600Y-131051D01*
X418195Y-131449D01*
X418898Y-131589D01*
X419600Y-131449D01*
X420195Y-131051D01*
X420593Y-130456D01*
X420733Y-129753D01*
X420593Y-129051D01*
X420195Y-128456D01*
X419600Y-128058D01*
X418898Y-127918D01*
X418195Y-128058D01*
X417600Y-128456D01*
X417142D01*
X417046Y-128311D01*
X416450Y-127913D01*
X415748Y-127774D01*
D02*
G37*
G36*
X98761Y-115911D02*
X98059Y-116051D01*
X97463Y-116448D01*
X97065Y-117044D01*
X96926Y-117746D01*
X97065Y-118448D01*
X97463Y-119044D01*
X98059Y-119442D01*
X98454Y-119520D01*
X98494Y-119552D01*
X98458Y-120088D01*
X98430Y-120102D01*
X98059Y-120176D01*
X97463Y-120574D01*
X97065Y-121169D01*
X96926Y-121871D01*
X97065Y-122574D01*
X97463Y-123169D01*
X98059Y-123567D01*
X98308Y-123617D01*
Y-124126D01*
X98059Y-124176D01*
X97463Y-124574D01*
X97065Y-125169D01*
X96926Y-125872D01*
X97065Y-126574D01*
X97463Y-127169D01*
X98059Y-127567D01*
X98309Y-127617D01*
Y-128127D01*
X98059Y-128176D01*
X97463Y-128574D01*
X97065Y-129170D01*
X96926Y-129872D01*
X97065Y-130574D01*
X97463Y-131170D01*
X98059Y-131568D01*
X98761Y-131707D01*
X99463Y-131568D01*
X100059Y-131170D01*
X100456Y-130574D01*
X100596Y-129872D01*
X101060Y-129641D01*
X101432Y-129567D01*
X102027Y-129169D01*
X102425Y-128574D01*
X102565Y-127872D01*
X102425Y-127169D01*
X102027Y-126574D01*
X101432Y-126176D01*
X101060Y-126102D01*
X100596Y-125872D01*
X100456Y-125169D01*
X100059Y-124574D01*
X99463Y-124176D01*
X99214Y-124126D01*
Y-123617D01*
X99463Y-123567D01*
X100059Y-123169D01*
X100456Y-122574D01*
X100596Y-121871D01*
X101060Y-121641D01*
X101432Y-121567D01*
X102027Y-121169D01*
X102425Y-120574D01*
X102565Y-119871D01*
X102425Y-119169D01*
X102027Y-118574D01*
X101432Y-118176D01*
X101036Y-118097D01*
X100596Y-117746D01*
X100456Y-117044D01*
X100059Y-116448D01*
X99463Y-116051D01*
X98761Y-115911D01*
D02*
G37*
G36*
X619449Y-124202D02*
X618417Y-124338D01*
X617455Y-124736D01*
X616630Y-125370D01*
X615996Y-126196D01*
X615598Y-127157D01*
X615462Y-128189D01*
X615598Y-129221D01*
X615996Y-130182D01*
X616630Y-131008D01*
X617455Y-131642D01*
X618417Y-132040D01*
X619449Y-132176D01*
X620481Y-132040D01*
X621442Y-131642D01*
X622268Y-131008D01*
X622901Y-130182D01*
X623300Y-129221D01*
X623436Y-128189D01*
X623300Y-127157D01*
X622901Y-126196D01*
X622268Y-125370D01*
X621442Y-124736D01*
X620481Y-124338D01*
X619449Y-124202D01*
D02*
G37*
G36*
X609449D02*
X608417Y-124338D01*
X607455Y-124736D01*
X606630Y-125370D01*
X605996Y-126196D01*
X605598Y-127157D01*
X605462Y-128189D01*
X605598Y-129221D01*
X605996Y-130182D01*
X606630Y-131008D01*
X607455Y-131642D01*
X608417Y-132040D01*
X609449Y-132176D01*
X610481Y-132040D01*
X611442Y-131642D01*
X612268Y-131008D01*
X612901Y-130182D01*
X613300Y-129221D01*
X613436Y-128189D01*
X613300Y-127157D01*
X612901Y-126196D01*
X612268Y-125370D01*
X611442Y-124736D01*
X610481Y-124338D01*
X609449Y-124202D01*
D02*
G37*
G36*
X150233Y-125527D02*
X149530Y-125667D01*
X148935Y-126065D01*
X148537Y-126660D01*
X148398Y-127362D01*
X148537Y-128065D01*
X148935Y-128660D01*
X149097Y-128768D01*
X149329Y-129214D01*
X149207Y-129397D01*
X148931Y-129809D01*
X148791Y-130512D01*
X148931Y-131214D01*
X149329Y-131809D01*
X149924Y-132207D01*
X150627Y-132347D01*
X151329Y-132207D01*
X151924Y-131809D01*
X152322Y-131214D01*
X152462Y-130512D01*
X152322Y-129809D01*
X151924Y-129214D01*
X151763Y-129106D01*
X151531Y-128660D01*
X151653Y-128477D01*
X151928Y-128065D01*
X152068Y-127362D01*
X151928Y-126660D01*
X151531Y-126065D01*
X150935Y-125667D01*
X150233Y-125527D01*
D02*
G37*
G36*
X255906Y-129661D02*
X255203Y-129800D01*
X254608Y-130198D01*
X254210Y-130794D01*
X254070Y-131496D01*
X254210Y-132198D01*
X254608Y-132794D01*
X255203Y-133192D01*
X255906Y-133331D01*
X256608Y-133192D01*
X257203Y-132794D01*
X257601Y-132198D01*
X257741Y-131496D01*
X257601Y-130794D01*
X257203Y-130198D01*
X256608Y-129800D01*
X255906Y-129661D01*
D02*
G37*
G36*
X422835Y-129956D02*
X422132Y-130096D01*
X421537Y-130494D01*
X421139Y-131089D01*
X420999Y-131791D01*
X421139Y-132494D01*
X421537Y-133089D01*
X422132Y-133487D01*
X422835Y-133627D01*
X423537Y-133487D01*
X424132Y-133089D01*
X424530Y-132494D01*
X424670Y-131791D01*
X424530Y-131089D01*
X424132Y-130494D01*
X423537Y-130096D01*
X422835Y-129956D01*
D02*
G37*
G36*
X594488Y-130842D02*
X593786Y-130982D01*
X593190Y-131379D01*
X592793Y-131975D01*
X592653Y-132677D01*
X592793Y-133379D01*
X593190Y-133975D01*
X593786Y-134373D01*
X594488Y-134512D01*
X595190Y-134373D01*
X595786Y-133975D01*
X596184Y-133379D01*
X596323Y-132677D01*
X596184Y-131975D01*
X595786Y-131379D01*
X595190Y-130982D01*
X594488Y-130842D01*
D02*
G37*
G36*
X186847Y-133401D02*
X186145Y-133541D01*
X185549Y-133939D01*
X185151Y-134534D01*
X185012Y-135236D01*
X185151Y-135939D01*
X185549Y-136534D01*
X186145Y-136932D01*
X186847Y-137072D01*
X187549Y-136932D01*
X188145Y-136534D01*
X188542Y-135939D01*
X188682Y-135236D01*
X188542Y-134534D01*
X188145Y-133939D01*
X187549Y-133541D01*
X186847Y-133401D01*
D02*
G37*
G36*
X91044Y-136101D02*
X90342Y-136240D01*
X89747Y-136638D01*
X89349Y-137233D01*
X89299Y-137483D01*
X88789D01*
X88740Y-137233D01*
X88342Y-136638D01*
X87747Y-136240D01*
X87044Y-136101D01*
X86342Y-136240D01*
X85747Y-136638D01*
X85349Y-137233D01*
X85299Y-137483D01*
X84789D01*
X84740Y-137233D01*
X84342Y-136638D01*
X83747Y-136240D01*
X83044Y-136101D01*
X82342Y-136240D01*
X81747Y-136638D01*
X81349Y-137233D01*
X81299Y-137483D01*
X80789D01*
X80740Y-137233D01*
X80342Y-136638D01*
X79747Y-136240D01*
X79044Y-136101D01*
X78342Y-136240D01*
X77747Y-136638D01*
X77349Y-137233D01*
X77209Y-137936D01*
X77349Y-138638D01*
X77747Y-139234D01*
X78342Y-139631D01*
X79044Y-139771D01*
X79244Y-139731D01*
X79349Y-140259D01*
X79747Y-140855D01*
X80342Y-141253D01*
X81044Y-141392D01*
X81747Y-141253D01*
X82342Y-140855D01*
X82740Y-140259D01*
X82845Y-139731D01*
X83044Y-139771D01*
X83747Y-139631D01*
X84342Y-139234D01*
X84740Y-138638D01*
X84789Y-138389D01*
X85299D01*
X85349Y-138638D01*
X85747Y-139234D01*
X86342Y-139631D01*
X87044Y-139771D01*
X87244Y-139731D01*
X87349Y-140259D01*
X87747Y-140855D01*
X88342Y-141253D01*
X89044Y-141392D01*
X89747Y-141253D01*
X90342Y-140855D01*
X90740Y-140259D01*
X90845Y-139731D01*
X91044Y-139771D01*
X91747Y-139631D01*
X92342Y-139234D01*
X92740Y-138638D01*
X92880Y-137936D01*
X92740Y-137233D01*
X92342Y-136638D01*
X91747Y-136240D01*
X91044Y-136101D01*
D02*
G37*
G36*
X172674Y-136551D02*
X171971Y-136690D01*
X171376Y-137088D01*
X170978Y-137683D01*
X170868Y-138236D01*
X170311Y-138125D01*
X169609Y-138265D01*
X169014Y-138663D01*
X168616Y-139258D01*
X168476Y-139961D01*
X168616Y-140663D01*
X169014Y-141258D01*
X169609Y-141656D01*
X170311Y-141796D01*
X171014Y-141656D01*
X171609Y-141258D01*
X172007Y-140663D01*
X172117Y-140110D01*
X172674Y-140221D01*
X173376Y-140081D01*
X173971Y-139683D01*
X174369Y-139088D01*
X174509Y-138386D01*
X174369Y-137683D01*
X173971Y-137088D01*
X173376Y-136690D01*
X172674Y-136551D01*
D02*
G37*
G36*
X126307Y-134389D02*
X125605Y-134528D01*
X125010Y-134926D01*
X124612Y-135522D01*
X124472Y-136224D01*
X124612Y-136926D01*
X125010Y-137522D01*
X125605Y-137919D01*
X126307Y-138059D01*
X127010Y-137919D01*
X127534Y-137569D01*
X127766Y-137915D01*
X128361Y-138313D01*
X129063Y-138453D01*
X129766Y-138313D01*
X130361Y-137915D01*
X130759Y-137320D01*
X130836Y-136933D01*
X131346D01*
X131403Y-137222D01*
X131801Y-137817D01*
X132396Y-138215D01*
X133099Y-138355D01*
X133801Y-138215D01*
X134397Y-137817D01*
X134794Y-137222D01*
X134934Y-136519D01*
X134794Y-135817D01*
X134397Y-135222D01*
X133801Y-134824D01*
X133099Y-134684D01*
X132396Y-134824D01*
X131801Y-135222D01*
X131403Y-135817D01*
X131326Y-136204D01*
X130816D01*
X130759Y-135915D01*
X130361Y-135320D01*
X129766Y-134922D01*
X129063Y-134782D01*
X128361Y-134922D01*
X127837Y-135273D01*
X127605Y-134926D01*
X127010Y-134528D01*
X126307Y-134389D01*
D02*
G37*
G36*
X178185Y-131826D02*
X177483Y-131966D01*
X176888Y-132364D01*
X176490Y-132959D01*
X176350Y-133661D01*
X176490Y-134364D01*
X176866Y-134926D01*
X176928Y-135073D01*
Y-135399D01*
X176866Y-135546D01*
X176490Y-136109D01*
X176350Y-136811D01*
X176490Y-137513D01*
X176888Y-138109D01*
X177483Y-138507D01*
X178185Y-138646D01*
X178888Y-138507D01*
X179483Y-138109D01*
X179881Y-137513D01*
X180021Y-136811D01*
X179881Y-136109D01*
X179505Y-135546D01*
X179443Y-135399D01*
Y-135073D01*
X179505Y-134926D01*
X179881Y-134364D01*
X180021Y-133661D01*
X179881Y-132959D01*
X179483Y-132364D01*
X178888Y-131966D01*
X178185Y-131826D01*
D02*
G37*
G36*
X255906Y-135173D02*
X255203Y-135312D01*
X254608Y-135710D01*
X254210Y-136306D01*
X254070Y-137008D01*
X254210Y-137710D01*
X254608Y-138306D01*
X255203Y-138703D01*
X255906Y-138843D01*
X256608Y-138703D01*
X257203Y-138306D01*
X257601Y-137710D01*
X257741Y-137008D01*
X257601Y-136306D01*
X257203Y-135710D01*
X256608Y-135312D01*
X255906Y-135173D01*
D02*
G37*
G36*
X44001Y-135911D02*
X43298Y-136051D01*
X42703Y-136449D01*
X42305Y-137044D01*
X42165Y-137747D01*
X42305Y-138449D01*
X42703Y-139044D01*
X43298Y-139442D01*
X44001Y-139582D01*
X44703Y-139442D01*
X45298Y-139044D01*
X45696Y-138449D01*
X45836Y-137747D01*
X45696Y-137044D01*
X45298Y-136449D01*
X44703Y-136051D01*
X44001Y-135911D01*
D02*
G37*
G36*
X298031Y-131426D02*
X296974Y-131565D01*
X295988Y-131973D01*
X295142Y-132623D01*
X294493Y-133469D01*
X294085Y-134454D01*
X293945Y-135512D01*
X294085Y-136569D01*
X294493Y-137555D01*
X295142Y-138401D01*
X295988Y-139050D01*
X296974Y-139459D01*
X298031Y-139598D01*
X299089Y-139459D01*
X300075Y-139050D01*
X300921Y-138401D01*
X301570Y-137555D01*
X301978Y-136569D01*
X302118Y-135512D01*
X301978Y-134454D01*
X301570Y-133469D01*
X300921Y-132623D01*
X300075Y-131973D01*
X299089Y-131565D01*
X298031Y-131426D01*
D02*
G37*
G36*
X285827Y-135960D02*
X285124Y-136100D01*
X284529Y-136498D01*
X284131Y-137093D01*
X283992Y-137795D01*
X284131Y-138498D01*
X284529Y-139093D01*
X285124Y-139491D01*
X285827Y-139630D01*
X286529Y-139491D01*
X287124Y-139093D01*
X287522Y-138498D01*
X287662Y-137795D01*
X287522Y-137093D01*
X287124Y-136498D01*
X286529Y-136100D01*
X285827Y-135960D01*
D02*
G37*
G36*
X280709D02*
X280006Y-136100D01*
X279411Y-136498D01*
X279013Y-137093D01*
X278873Y-137795D01*
X279013Y-138498D01*
X279411Y-139093D01*
X280006Y-139491D01*
X280709Y-139630D01*
X281411Y-139491D01*
X282006Y-139093D01*
X282404Y-138498D01*
X282544Y-137795D01*
X282404Y-137093D01*
X282006Y-136498D01*
X281411Y-136100D01*
X280709Y-135960D01*
D02*
G37*
G36*
X223209Y-135980D02*
X222506Y-136119D01*
X221911Y-136517D01*
X221513Y-137113D01*
X221373Y-137815D01*
X221513Y-138517D01*
X221911Y-139113D01*
X222506Y-139511D01*
X223209Y-139650D01*
X223911Y-139511D01*
X224506Y-139113D01*
X224904Y-138517D01*
X225044Y-137815D01*
X224904Y-137113D01*
X224506Y-136517D01*
X223911Y-136119D01*
X223209Y-135980D01*
D02*
G37*
G36*
X321260Y-131484D02*
X320177Y-131626D01*
X319167Y-132045D01*
X318300Y-132710D01*
X317635Y-133577D01*
X317217Y-134586D01*
X317074Y-135669D01*
X317217Y-136752D01*
X317635Y-137762D01*
X318300Y-138629D01*
X319167Y-139294D01*
X320177Y-139712D01*
X321260Y-139855D01*
X322343Y-139712D01*
X323353Y-139294D01*
X324219Y-138629D01*
X324885Y-137762D01*
X325303Y-136752D01*
X325445Y-135669D01*
X325303Y-134586D01*
X324885Y-133577D01*
X324219Y-132710D01*
X323353Y-132045D01*
X322343Y-131626D01*
X321260Y-131484D01*
D02*
G37*
G36*
X68889Y-135618D02*
X68187Y-135758D01*
X67591Y-136156D01*
X67194Y-136751D01*
X67054Y-137453D01*
X67194Y-138156D01*
X67591Y-138751D01*
X68187Y-139149D01*
X68889Y-139289D01*
X69591Y-139149D01*
X69695Y-139080D01*
X69904Y-139393D01*
X70499Y-139790D01*
X71202Y-139930D01*
X71904Y-139790D01*
X72500Y-139393D01*
X72897Y-138797D01*
X73037Y-138095D01*
X72897Y-137393D01*
X72500Y-136797D01*
X71904Y-136399D01*
X71202Y-136260D01*
X70499Y-136399D01*
X70396Y-136469D01*
X70187Y-136156D01*
X69591Y-135758D01*
X68889Y-135618D01*
D02*
G37*
G36*
X204193Y-136422D02*
X203491Y-136562D01*
X202895Y-136959D01*
X202497Y-137555D01*
X202358Y-138257D01*
X202497Y-138959D01*
X202895Y-139555D01*
X203491Y-139953D01*
X204193Y-140092D01*
X204895Y-139953D01*
X205491Y-139555D01*
X205889Y-138959D01*
X206028Y-138257D01*
X205889Y-137555D01*
X205491Y-136959D01*
X204895Y-136562D01*
X204193Y-136422D01*
D02*
G37*
G36*
X199193Y-136844D02*
X198491Y-136984D01*
X197895Y-137382D01*
X197497Y-137977D01*
X197358Y-138680D01*
X197497Y-139382D01*
X197895Y-139977D01*
X198491Y-140375D01*
X199193Y-140515D01*
X199895Y-140375D01*
X200491Y-139977D01*
X200888Y-139382D01*
X201028Y-138680D01*
X200888Y-137977D01*
X200491Y-137382D01*
X199895Y-136984D01*
X199193Y-136844D01*
D02*
G37*
G36*
X228209Y-136885D02*
X227506Y-137025D01*
X226911Y-137423D01*
X226513Y-138018D01*
X226373Y-138721D01*
X226513Y-139423D01*
X226911Y-140018D01*
X227506Y-140416D01*
X228209Y-140556D01*
X228911Y-140416D01*
X229506Y-140018D01*
X229904Y-139423D01*
X230044Y-138721D01*
X229904Y-138018D01*
X229506Y-137423D01*
X228911Y-137025D01*
X228209Y-136885D01*
D02*
G37*
G36*
X233209Y-137397D02*
X232506Y-137537D01*
X231911Y-137935D01*
X231513Y-138530D01*
X231373Y-139232D01*
X231513Y-139935D01*
X231911Y-140530D01*
X232506Y-140928D01*
X233209Y-141068D01*
X233911Y-140928D01*
X234506Y-140530D01*
X234904Y-139935D01*
X235044Y-139232D01*
X234904Y-138530D01*
X234506Y-137935D01*
X233911Y-137537D01*
X233209Y-137397D01*
D02*
G37*
G36*
X162241Y-138169D02*
X161538Y-138309D01*
X160943Y-138706D01*
X160545Y-139302D01*
X160405Y-140004D01*
X160545Y-140706D01*
X160943Y-141302D01*
X161538Y-141700D01*
X162241Y-141839D01*
X162943Y-141700D01*
X163538Y-141302D01*
X163936Y-140706D01*
X164076Y-140004D01*
X163936Y-139302D01*
X163538Y-138706D01*
X162943Y-138309D01*
X162241Y-138169D01*
D02*
G37*
G36*
X150394Y-138322D02*
X149691Y-138462D01*
X149096Y-138860D01*
X148698Y-139455D01*
X148558Y-140157D01*
X148698Y-140860D01*
X149096Y-141455D01*
X149691Y-141853D01*
X150394Y-141993D01*
X151096Y-141853D01*
X151691Y-141455D01*
X152089Y-140860D01*
X152229Y-140157D01*
X152089Y-139455D01*
X151691Y-138860D01*
X151096Y-138462D01*
X150394Y-138322D01*
D02*
G37*
G36*
X276083Y-139306D02*
X275380Y-139446D01*
X274785Y-139844D01*
X274387Y-140439D01*
X274247Y-141142D01*
X274387Y-141844D01*
X274785Y-142439D01*
X275380Y-142837D01*
X276083Y-142977D01*
X276785Y-142837D01*
X277380Y-142439D01*
X277778Y-141844D01*
X277918Y-141142D01*
X277778Y-140439D01*
X277380Y-139844D01*
X276785Y-139446D01*
X276083Y-139306D01*
D02*
G37*
G36*
X255906Y-140291D02*
X255203Y-140430D01*
X254608Y-140828D01*
X254210Y-141424D01*
X254070Y-142126D01*
X254210Y-142828D01*
X254608Y-143424D01*
X255203Y-143822D01*
X255906Y-143961D01*
X256608Y-143822D01*
X257203Y-143424D01*
X257601Y-142828D01*
X257741Y-142126D01*
X257601Y-141424D01*
X257203Y-140828D01*
X256608Y-140430D01*
X255906Y-140291D01*
D02*
G37*
G36*
X284252Y-142259D02*
X283550Y-142399D01*
X282954Y-142797D01*
X282556Y-143392D01*
X282417Y-144095D01*
X282556Y-144797D01*
X282954Y-145392D01*
X283550Y-145790D01*
X284252Y-145930D01*
X284954Y-145790D01*
X285550Y-145392D01*
X285947Y-144797D01*
X286087Y-144095D01*
X285947Y-143392D01*
X285550Y-142797D01*
X284954Y-142399D01*
X284252Y-142259D01*
D02*
G37*
G36*
X591339Y-142653D02*
X590636Y-142793D01*
X590041Y-143191D01*
X589643Y-143786D01*
X589503Y-144488D01*
X589643Y-145191D01*
X590041Y-145786D01*
X590636Y-146184D01*
X591339Y-146324D01*
X592041Y-146184D01*
X592636Y-145786D01*
X593034Y-145191D01*
X593174Y-144488D01*
X593034Y-143786D01*
X592636Y-143191D01*
X592041Y-142793D01*
X591339Y-142653D01*
D02*
G37*
G36*
X496063Y-143440D02*
X495361Y-143580D01*
X494765Y-143978D01*
X494367Y-144573D01*
X494228Y-145276D01*
X494367Y-145978D01*
X494765Y-146573D01*
X495361Y-146971D01*
X496063Y-147111D01*
X496765Y-146971D01*
X497361Y-146573D01*
X497759Y-145978D01*
X497898Y-145276D01*
X497759Y-144573D01*
X497361Y-143978D01*
X496765Y-143580D01*
X496063Y-143440D01*
D02*
G37*
G36*
X500394Y-143834D02*
X499691Y-143974D01*
X499096Y-144372D01*
X498698Y-144967D01*
X498558Y-145669D01*
X498698Y-146372D01*
X499096Y-146967D01*
X499691Y-147365D01*
X500394Y-147504D01*
X501096Y-147365D01*
X501691Y-146967D01*
X502089Y-146372D01*
X502229Y-145669D01*
X502089Y-144967D01*
X501691Y-144372D01*
X501096Y-143974D01*
X500394Y-143834D01*
D02*
G37*
G36*
X491732Y-143440D02*
X491030Y-143580D01*
X490435Y-143978D01*
X490037Y-144573D01*
X489897Y-145276D01*
X490037Y-145978D01*
X490435Y-146573D01*
X491030Y-146971D01*
X491121Y-146989D01*
Y-147499D01*
X491030Y-147517D01*
X490435Y-147915D01*
X490037Y-148510D01*
X489897Y-149213D01*
X490037Y-149915D01*
X490435Y-150510D01*
X491030Y-150908D01*
X491732Y-151048D01*
X492435Y-150908D01*
X493030Y-150510D01*
X493428Y-149915D01*
X493568Y-149213D01*
X493428Y-148510D01*
X493030Y-147915D01*
X492435Y-147517D01*
X492344Y-147499D01*
Y-146989D01*
X492435Y-146971D01*
X493030Y-146573D01*
X493428Y-145978D01*
X493568Y-145276D01*
X493428Y-144573D01*
X493030Y-143978D01*
X492435Y-143580D01*
X491732Y-143440D01*
D02*
G37*
G36*
X619449Y-144202D02*
X618417Y-144338D01*
X617455Y-144736D01*
X616630Y-145370D01*
X615996Y-146196D01*
X615598Y-147157D01*
X615462Y-148189D01*
X615598Y-149221D01*
X615996Y-150182D01*
X616630Y-151008D01*
X617455Y-151642D01*
X618417Y-152040D01*
X619449Y-152176D01*
X620481Y-152040D01*
X621442Y-151642D01*
X622268Y-151008D01*
X622901Y-150182D01*
X623300Y-149221D01*
X623436Y-148189D01*
X623300Y-147157D01*
X622901Y-146196D01*
X622268Y-145370D01*
X621442Y-144736D01*
X620481Y-144338D01*
X619449Y-144202D01*
D02*
G37*
G36*
X609449D02*
X608417Y-144338D01*
X607455Y-144736D01*
X606630Y-145370D01*
X605996Y-146196D01*
X605598Y-147157D01*
X605462Y-148189D01*
X605598Y-149221D01*
X605996Y-150182D01*
X606630Y-151008D01*
X607455Y-151642D01*
X608417Y-152040D01*
X609449Y-152176D01*
X610481Y-152040D01*
X611442Y-151642D01*
X612268Y-151008D01*
X612901Y-150182D01*
X613300Y-149221D01*
X613436Y-148189D01*
X613300Y-147157D01*
X612901Y-146196D01*
X612268Y-145370D01*
X611442Y-144736D01*
X610481Y-144338D01*
X609449Y-144202D01*
D02*
G37*
G36*
X255512Y-145015D02*
X254809Y-145155D01*
X254214Y-145553D01*
X253816Y-146148D01*
X253677Y-146850D01*
X253816Y-147553D01*
X254214Y-148148D01*
X254809Y-148546D01*
X255512Y-148686D01*
X256060Y-148577D01*
X256255Y-149048D01*
X256183Y-149096D01*
X255785Y-149691D01*
X255645Y-150394D01*
X255785Y-151096D01*
X256183Y-151691D01*
X256778Y-152089D01*
X257480Y-152229D01*
X258183Y-152089D01*
X258778Y-151691D01*
X259176Y-151096D01*
X259316Y-150394D01*
X259176Y-149691D01*
X258778Y-149096D01*
X258183Y-148698D01*
X257480Y-148558D01*
X256932Y-148668D01*
X256737Y-148196D01*
X256809Y-148148D01*
X257207Y-147553D01*
X257347Y-146850D01*
X257207Y-146148D01*
X256809Y-145553D01*
X256214Y-145155D01*
X255512Y-145015D01*
D02*
G37*
G36*
X282058Y-149381D02*
X281356Y-149521D01*
X280761Y-149919D01*
X280363Y-150514D01*
X280223Y-151217D01*
X280363Y-151919D01*
X280761Y-152515D01*
X281356Y-152912D01*
X282058Y-153052D01*
X282761Y-152912D01*
X283356Y-152515D01*
X283754Y-151919D01*
X283893Y-151217D01*
X283754Y-150514D01*
X283356Y-149919D01*
X282761Y-149521D01*
X282058Y-149381D01*
D02*
G37*
G36*
X276083Y-150724D02*
X275380Y-150864D01*
X274785Y-151261D01*
X274387Y-151857D01*
X274247Y-152559D01*
X274387Y-153261D01*
X274785Y-153857D01*
X275380Y-154255D01*
X276083Y-154394D01*
X276785Y-154255D01*
X277380Y-153857D01*
X277778Y-153261D01*
X277918Y-152559D01*
X277778Y-151857D01*
X277380Y-151261D01*
X276785Y-150864D01*
X276083Y-150724D01*
D02*
G37*
G36*
X285384Y-152657D02*
X284682Y-152797D01*
X284086Y-153194D01*
X283689Y-153790D01*
X283584Y-154317D01*
X283479Y-154394D01*
X283131Y-154525D01*
X283070Y-154530D01*
X282592Y-154210D01*
X281890Y-154070D01*
X281187Y-154210D01*
X280592Y-154608D01*
X280194Y-155203D01*
X280054Y-155905D01*
X280194Y-156608D01*
X280592Y-157203D01*
X281187Y-157601D01*
X281890Y-157741D01*
X282592Y-157601D01*
X283188Y-157203D01*
X283585Y-156608D01*
X283690Y-156081D01*
X283795Y-156004D01*
X284143Y-155873D01*
X284204Y-155868D01*
X284682Y-156188D01*
X285384Y-156327D01*
X286087Y-156188D01*
X286682Y-155790D01*
X287080Y-155194D01*
X287220Y-154492D01*
X287080Y-153790D01*
X286682Y-153194D01*
X286087Y-152797D01*
X285384Y-152657D01*
D02*
G37*
G36*
X366043Y-152102D02*
X365341Y-152241D01*
X364746Y-152639D01*
X364348Y-153235D01*
X364208Y-153937D01*
X364348Y-154639D01*
X364746Y-155235D01*
X365341Y-155633D01*
X366043Y-155772D01*
X366746Y-155633D01*
X367341Y-155235D01*
X367739Y-154639D01*
X367879Y-153937D01*
X367739Y-153235D01*
X367341Y-152639D01*
X366746Y-152241D01*
X366043Y-152102D01*
D02*
G37*
G36*
X302083Y-151461D02*
X293980D01*
Y-159563D01*
X302083D01*
Y-151461D01*
D02*
G37*
G36*
X363386Y-158795D02*
X362684Y-158934D01*
X362088Y-159332D01*
X361783Y-159788D01*
X361331Y-159850D01*
X361205Y-159823D01*
X361140Y-159726D01*
X360545Y-159328D01*
X359842Y-159188D01*
X359140Y-159328D01*
X358545Y-159726D01*
X358147Y-160321D01*
X358007Y-161024D01*
X358147Y-161726D01*
X358545Y-162321D01*
X359140Y-162719D01*
X359842Y-162859D01*
X360545Y-162719D01*
X361140Y-162321D01*
X361445Y-161865D01*
X361897Y-161804D01*
X362023Y-161831D01*
X362088Y-161928D01*
X362684Y-162326D01*
X363386Y-162465D01*
X364088Y-162326D01*
X364684Y-161928D01*
X365081Y-161332D01*
X365221Y-160630D01*
X365081Y-159928D01*
X364684Y-159332D01*
X364088Y-158934D01*
X363386Y-158795D01*
D02*
G37*
G36*
X586614Y-156826D02*
X585912Y-156966D01*
X585316Y-157364D01*
X584919Y-157959D01*
X584779Y-158661D01*
X584919Y-159364D01*
X585316Y-159959D01*
X585912Y-160357D01*
X586614Y-160497D01*
X587317Y-160357D01*
X587912Y-159959D01*
X588310Y-159364D01*
X588449Y-158661D01*
X588310Y-157959D01*
X587912Y-157364D01*
X587317Y-156966D01*
X586614Y-156826D01*
D02*
G37*
G36*
X325409Y-151520D02*
X317110D01*
Y-159575D01*
X316531Y-159962D01*
X316133Y-160557D01*
X316075Y-160849D01*
X315652Y-160887D01*
X315560Y-160874D01*
X315176Y-160299D01*
X314581Y-159901D01*
X313878Y-159761D01*
X313176Y-159901D01*
X312581Y-160299D01*
X312183Y-160894D01*
X312043Y-161597D01*
X312183Y-162299D01*
X312581Y-162894D01*
X313176Y-163292D01*
X313878Y-163432D01*
X314581Y-163292D01*
X315176Y-162894D01*
X315574Y-162299D01*
X315632Y-162007D01*
X316054Y-161969D01*
X316146Y-161983D01*
X316531Y-162558D01*
X317126Y-162955D01*
X317828Y-163095D01*
X318531Y-162955D01*
X319126Y-162558D01*
X319524Y-161962D01*
X319664Y-161260D01*
X319524Y-160557D01*
X319364Y-160319D01*
X319632Y-159819D01*
X325409D01*
Y-151520D01*
D02*
G37*
G36*
X-3528Y-152395D02*
X-13402D01*
Y-162269D01*
X-3528D01*
Y-152395D01*
D02*
G37*
G36*
X367717Y-158795D02*
X367014Y-158934D01*
X366419Y-159332D01*
X366021Y-159928D01*
X365881Y-160630D01*
X366021Y-161332D01*
X366419Y-161928D01*
X367014Y-162326D01*
X367717Y-162465D01*
X368419Y-162326D01*
X369014Y-161928D01*
X369412Y-161332D01*
X369552Y-160630D01*
X369412Y-159928D01*
X369014Y-159332D01*
X368419Y-158934D01*
X367717Y-158795D01*
D02*
G37*
G36*
X378346Y-159976D02*
X377644Y-160116D01*
X377049Y-160513D01*
X376651Y-161109D01*
X376511Y-161811D01*
X376651Y-162513D01*
X377049Y-163109D01*
X377644Y-163507D01*
X378346Y-163646D01*
X379049Y-163507D01*
X379644Y-163109D01*
X380042Y-162513D01*
X380182Y-161811D01*
X380042Y-161109D01*
X379644Y-160513D01*
X379049Y-160116D01*
X378346Y-159976D01*
D02*
G37*
G36*
X383083Y-160004D02*
X382380Y-160143D01*
X381785Y-160541D01*
X381387Y-161137D01*
X381247Y-161839D01*
X381387Y-162541D01*
X381785Y-163137D01*
X382380Y-163535D01*
X383083Y-163674D01*
X383785Y-163535D01*
X384380Y-163137D01*
X384778Y-162541D01*
X384918Y-161839D01*
X384778Y-161137D01*
X384380Y-160541D01*
X383785Y-160143D01*
X383083Y-160004D01*
D02*
G37*
G36*
X388189Y-160370D02*
X387487Y-160509D01*
X386891Y-160907D01*
X386493Y-161502D01*
X386354Y-162205D01*
X386493Y-162907D01*
X386891Y-163502D01*
X387487Y-163900D01*
X388189Y-164040D01*
X388891Y-163900D01*
X389487Y-163502D01*
X389884Y-162907D01*
X390024Y-162205D01*
X389884Y-161502D01*
X389487Y-160907D01*
X388891Y-160509D01*
X388189Y-160370D01*
D02*
G37*
G36*
X373228Y-160763D02*
X372526Y-160903D01*
X371931Y-161301D01*
X371533Y-161896D01*
X371393Y-162598D01*
X371533Y-163301D01*
X371931Y-163896D01*
X372526Y-164294D01*
X373228Y-164434D01*
X373931Y-164294D01*
X374526Y-163896D01*
X374924Y-163301D01*
X375064Y-162598D01*
X374924Y-161896D01*
X374526Y-161301D01*
X373931Y-160903D01*
X373228Y-160763D01*
D02*
G37*
G36*
X582165Y-162062D02*
X581463Y-162202D01*
X580868Y-162600D01*
X580470Y-163195D01*
X580330Y-163898D01*
X580470Y-164600D01*
X580868Y-165195D01*
X581463Y-165593D01*
X582165Y-165733D01*
X582868Y-165593D01*
X583463Y-165195D01*
X583861Y-164600D01*
X584001Y-163898D01*
X583861Y-163195D01*
X583463Y-162600D01*
X582868Y-162202D01*
X582165Y-162062D01*
D02*
G37*
G36*
X78268Y-152746D02*
X76895Y-152881D01*
X75576Y-153281D01*
X74360Y-153931D01*
X73294Y-154806D01*
X72419Y-155872D01*
X71769Y-157088D01*
X71369Y-158407D01*
X71234Y-159780D01*
X71369Y-161152D01*
X71769Y-162471D01*
X72419Y-163687D01*
X73294Y-164753D01*
X74360Y-165628D01*
X75576Y-166278D01*
X76895Y-166678D01*
X78268Y-166813D01*
X79640Y-166678D01*
X80959Y-166278D01*
X82175Y-165628D01*
X83241Y-164753D01*
X84116Y-163687D01*
X84766Y-162471D01*
X85166Y-161152D01*
X85302Y-159780D01*
X85166Y-158407D01*
X84766Y-157088D01*
X84116Y-155872D01*
X83241Y-154806D01*
X82175Y-153931D01*
X80959Y-153281D01*
X79640Y-152881D01*
X78268Y-152746D01*
D02*
G37*
G36*
X348031Y-163913D02*
X347329Y-164052D01*
X346734Y-164450D01*
X346336Y-165046D01*
X346196Y-165748D01*
X346336Y-166450D01*
X346734Y-167046D01*
X347329Y-167444D01*
X348031Y-167583D01*
X348734Y-167444D01*
X349329Y-167046D01*
X349727Y-166450D01*
X349867Y-165748D01*
X349727Y-165046D01*
X349329Y-164450D01*
X348734Y-164052D01*
X348031Y-163913D01*
D02*
G37*
G36*
X310236D02*
X309534Y-164052D01*
X308939Y-164450D01*
X308541Y-165046D01*
X308401Y-165748D01*
X308541Y-166450D01*
X308939Y-167046D01*
X309534Y-167444D01*
X310236Y-167583D01*
X310939Y-167444D01*
X311534Y-167046D01*
X311932Y-166450D01*
X312071Y-165748D01*
X311932Y-165046D01*
X311534Y-164450D01*
X310939Y-164052D01*
X310236Y-163913D01*
D02*
G37*
G36*
X422835Y-164449D02*
X422132Y-164589D01*
X421537Y-164987D01*
X421139Y-165582D01*
X420999Y-166284D01*
X421139Y-166987D01*
X421537Y-167582D01*
X422132Y-167980D01*
X422835Y-168120D01*
X423537Y-167980D01*
X424132Y-167582D01*
X424530Y-166987D01*
X424670Y-166284D01*
X424530Y-165582D01*
X424132Y-164987D01*
X423537Y-164589D01*
X422835Y-164449D01*
D02*
G37*
G36*
X321260Y-164306D02*
X320557Y-164446D01*
X319962Y-164844D01*
X319564Y-165439D01*
X319425Y-166142D01*
X319564Y-166844D01*
X319962Y-167439D01*
X320557Y-167837D01*
X321260Y-167977D01*
X321962Y-167837D01*
X322214Y-167669D01*
X322324Y-167833D01*
X322920Y-168231D01*
X323622Y-168371D01*
X324324Y-168231D01*
X324920Y-167833D01*
X325318Y-167238D01*
X325457Y-166535D01*
X325318Y-165833D01*
X324920Y-165238D01*
X324324Y-164840D01*
X323622Y-164700D01*
X322920Y-164840D01*
X322667Y-165008D01*
X322558Y-164844D01*
X321962Y-164446D01*
X321260Y-164306D01*
D02*
G37*
G36*
X427843Y-165131D02*
X427141Y-165271D01*
X426545Y-165669D01*
X426148Y-166264D01*
X426008Y-166966D01*
X426148Y-167669D01*
X426545Y-168264D01*
X427141Y-168662D01*
X427843Y-168802D01*
X428545Y-168662D01*
X429141Y-168264D01*
X429539Y-167669D01*
X429678Y-166966D01*
X429539Y-166264D01*
X429141Y-165669D01*
X428545Y-165271D01*
X427843Y-165131D01*
D02*
G37*
G36*
X378594D02*
X377891Y-165271D01*
X377296Y-165669D01*
X376898Y-166264D01*
X376759Y-166966D01*
X376898Y-167669D01*
X377296Y-168264D01*
X377891Y-168662D01*
X378594Y-168802D01*
X379296Y-168662D01*
X379891Y-168264D01*
X380289Y-167669D01*
X380429Y-166966D01*
X380289Y-166264D01*
X379891Y-165669D01*
X379296Y-165271D01*
X378594Y-165131D01*
D02*
G37*
G36*
X342808D02*
X342106Y-165271D01*
X341510Y-165669D01*
X341112Y-166264D01*
X340973Y-166966D01*
X341112Y-167669D01*
X341510Y-168264D01*
X342106Y-168662D01*
X342808Y-168802D01*
X343510Y-168662D01*
X344106Y-168264D01*
X344504Y-167669D01*
X344643Y-166966D01*
X344504Y-166264D01*
X344106Y-165669D01*
X343510Y-165271D01*
X342808Y-165131D01*
D02*
G37*
G36*
X218110Y-157750D02*
X216934Y-157866D01*
X215803Y-158209D01*
X214761Y-158767D01*
X213847Y-159516D01*
X213097Y-160430D01*
X212540Y-161472D01*
X212197Y-162603D01*
X212081Y-163779D01*
X212197Y-164956D01*
X212540Y-166087D01*
X213097Y-167129D01*
X213847Y-168043D01*
X214761Y-168792D01*
X215803Y-169350D01*
X216934Y-169693D01*
X218110Y-169808D01*
X219286Y-169693D01*
X220417Y-169350D01*
X221460Y-168792D01*
X222373Y-168043D01*
X223123Y-167129D01*
X223680Y-166087D01*
X224023Y-164956D01*
X224139Y-163779D01*
X224023Y-162603D01*
X223680Y-161472D01*
X223123Y-160430D01*
X222373Y-159516D01*
X221460Y-158767D01*
X220417Y-158209D01*
X219286Y-157866D01*
X218110Y-157750D01*
D02*
G37*
G36*
X58268D02*
X57091Y-157866D01*
X55961Y-158209D01*
X54918Y-158767D01*
X54005Y-159516D01*
X53255Y-160430D01*
X52698Y-161472D01*
X52355Y-162603D01*
X52239Y-163779D01*
X52355Y-164956D01*
X52698Y-166087D01*
X53255Y-167129D01*
X54005Y-168043D01*
X54918Y-168792D01*
X55961Y-169350D01*
X57091Y-169693D01*
X58268Y-169808D01*
X59444Y-169693D01*
X60575Y-169350D01*
X61617Y-168792D01*
X62531Y-168043D01*
X63281Y-167129D01*
X63838Y-166087D01*
X64181Y-164956D01*
X64297Y-163779D01*
X64181Y-162603D01*
X63838Y-161472D01*
X63281Y-160430D01*
X62531Y-159516D01*
X61617Y-158767D01*
X60575Y-158209D01*
X59444Y-157866D01*
X58268Y-157750D01*
D02*
G37*
G36*
X383071Y-166275D02*
X382369Y-166415D01*
X381773Y-166813D01*
X381375Y-167408D01*
X381236Y-168110D01*
X381375Y-168813D01*
X381773Y-169408D01*
X382369Y-169806D01*
X383071Y-169946D01*
X383773Y-169806D01*
X384369Y-169408D01*
X384766Y-168813D01*
X384906Y-168110D01*
X384766Y-167408D01*
X384369Y-166813D01*
X383773Y-166415D01*
X383071Y-166275D01*
D02*
G37*
G36*
X393701Y-167062D02*
X392999Y-167202D01*
X392403Y-167600D01*
X392005Y-168195D01*
X391865Y-168898D01*
X392005Y-169600D01*
X392403Y-170195D01*
X392999Y-170593D01*
X393701Y-170733D01*
X394403Y-170593D01*
X394999Y-170195D01*
X395396Y-169600D01*
X395536Y-168898D01*
X395396Y-168195D01*
X394999Y-167600D01*
X394403Y-167202D01*
X393701Y-167062D01*
D02*
G37*
G36*
X581890Y-172180D02*
X581187Y-172320D01*
X580592Y-172718D01*
X580194Y-173313D01*
X580055Y-174016D01*
X580194Y-174718D01*
X580592Y-175313D01*
X581187Y-175711D01*
X581890Y-175851D01*
X582592Y-175711D01*
X583187Y-175313D01*
X583585Y-174718D01*
X583725Y-174016D01*
X583585Y-173313D01*
X583187Y-172718D01*
X582592Y-172320D01*
X581890Y-172180D01*
D02*
G37*
G36*
X421313Y-172949D02*
X420611Y-173089D01*
X420015Y-173486D01*
X419617Y-174082D01*
X419478Y-174784D01*
X419514Y-174966D01*
X419096Y-175049D01*
X418500Y-175447D01*
X418102Y-176042D01*
X417963Y-176745D01*
X418102Y-177447D01*
X418500Y-178042D01*
X419096Y-178440D01*
X419798Y-178580D01*
X420500Y-178440D01*
X421096Y-178042D01*
X421493Y-177447D01*
X421633Y-176745D01*
X421597Y-176563D01*
X422015Y-176480D01*
X422611Y-176082D01*
X423009Y-175487D01*
X423148Y-174784D01*
X423009Y-174082D01*
X422611Y-173486D01*
X422015Y-173089D01*
X421313Y-172949D01*
D02*
G37*
G36*
X200610Y-164846D02*
X199238Y-164981D01*
X197918Y-165381D01*
X196703Y-166031D01*
X195637Y-166906D01*
X194762Y-167972D01*
X194112Y-169188D01*
X193712Y-170507D01*
X193576Y-171879D01*
X193712Y-173252D01*
X194112Y-174571D01*
X194762Y-175787D01*
X195637Y-176853D01*
X196703Y-177728D01*
X197918Y-178378D01*
X199238Y-178778D01*
X200610Y-178913D01*
X201982Y-178778D01*
X203302Y-178378D01*
X204518Y-177728D01*
X205584Y-176853D01*
X206459Y-175787D01*
X207109Y-174571D01*
X207509Y-173252D01*
X207644Y-171879D01*
X207509Y-170507D01*
X207109Y-169188D01*
X206459Y-167972D01*
X205584Y-166906D01*
X204518Y-166031D01*
X203302Y-165381D01*
X201982Y-164981D01*
X200610Y-164846D01*
D02*
G37*
G36*
X-10630Y-176511D02*
X-11332Y-176651D01*
X-11928Y-177049D01*
X-12325Y-177644D01*
X-12465Y-178347D01*
X-12325Y-179049D01*
X-11928Y-179644D01*
X-11332Y-180042D01*
X-10630Y-180182D01*
X-9928Y-180042D01*
X-9332Y-179644D01*
X-8934Y-179049D01*
X-8795Y-178347D01*
X-8934Y-177644D01*
X-9332Y-177049D01*
X-9928Y-176651D01*
X-10630Y-176511D01*
D02*
G37*
G36*
X586221Y-176905D02*
X585518Y-177045D01*
X584923Y-177442D01*
X584525Y-178038D01*
X584385Y-178740D01*
X584525Y-179443D01*
X584923Y-180038D01*
X585518Y-180436D01*
X586221Y-180575D01*
X586923Y-180436D01*
X587518Y-180038D01*
X587916Y-179443D01*
X588056Y-178740D01*
X587916Y-178038D01*
X587518Y-177442D01*
X586923Y-177045D01*
X586221Y-176905D01*
D02*
G37*
G36*
X426772Y-177692D02*
X426069Y-177832D01*
X425474Y-178230D01*
X425076Y-178825D01*
X424936Y-179528D01*
X425076Y-180230D01*
X425474Y-180825D01*
X426069Y-181223D01*
X426772Y-181363D01*
X427474Y-181223D01*
X428069Y-180825D01*
X428467Y-180230D01*
X428607Y-179528D01*
X428467Y-178825D01*
X428069Y-178230D01*
X427474Y-177832D01*
X426772Y-177692D01*
D02*
G37*
G36*
X334252Y-178480D02*
X333550Y-178619D01*
X332954Y-179017D01*
X332556Y-179613D01*
X332417Y-180315D01*
X332556Y-181017D01*
X332954Y-181613D01*
X333550Y-182010D01*
X334252Y-182150D01*
X334954Y-182010D01*
X335550Y-181613D01*
X335551Y-181610D01*
X336082Y-181716D01*
X336100Y-181805D01*
X336498Y-182400D01*
X337093Y-182798D01*
X337795Y-182938D01*
X338498Y-182798D01*
X339093Y-182400D01*
X339491Y-181805D01*
X339631Y-181102D01*
X339491Y-180400D01*
X339093Y-179805D01*
X338498Y-179407D01*
X337795Y-179267D01*
X337093Y-179407D01*
X336498Y-179805D01*
X336496Y-179807D01*
X335965Y-179701D01*
X335947Y-179613D01*
X335550Y-179017D01*
X334954Y-178619D01*
X334252Y-178480D01*
D02*
G37*
G36*
X326705Y-177224D02*
X326003Y-177364D01*
X325407Y-177761D01*
X325009Y-178357D01*
X324870Y-179059D01*
X325009Y-179762D01*
X325407Y-180357D01*
X326003Y-180755D01*
X326705Y-180894D01*
X327407Y-180755D01*
X327610Y-180619D01*
X327971Y-180980D01*
X327832Y-181187D01*
X327692Y-181890D01*
X327786Y-182359D01*
X327698Y-182691D01*
X327429Y-182889D01*
X326956Y-182983D01*
X326529Y-183268D01*
X326181Y-183342D01*
X325834Y-183268D01*
X325407Y-182983D01*
X324705Y-182843D01*
X324003Y-182983D01*
X323407Y-183380D01*
X323009Y-183976D01*
X322870Y-184678D01*
X323009Y-185381D01*
X323407Y-185976D01*
X324003Y-186374D01*
X324705Y-186513D01*
X325407Y-186374D01*
X325834Y-186089D01*
X326181Y-186014D01*
X326529Y-186089D01*
X326956Y-186374D01*
X327658Y-186513D01*
X328360Y-186374D01*
X328956Y-185976D01*
X329353Y-185381D01*
X329493Y-184678D01*
X329400Y-184209D01*
X329487Y-183877D01*
X329757Y-183679D01*
X330230Y-183585D01*
X330825Y-183187D01*
X331223Y-182592D01*
X331363Y-181890D01*
X331223Y-181187D01*
X330825Y-180592D01*
X330230Y-180194D01*
X329528Y-180054D01*
X328825Y-180194D01*
X328622Y-180330D01*
X328262Y-179969D01*
X328401Y-179762D01*
X328540Y-179059D01*
X328401Y-178357D01*
X328003Y-177761D01*
X327407Y-177364D01*
X326705Y-177224D01*
D02*
G37*
G36*
X390462Y-179645D02*
X389649Y-179807D01*
X388960Y-180267D01*
X388500Y-180956D01*
X388338Y-181769D01*
X388500Y-182582D01*
X388960Y-183271D01*
X389649Y-183731D01*
X390462Y-183893D01*
X391275Y-183731D01*
X391964Y-183271D01*
X392424Y-182582D01*
X392586Y-181769D01*
X392424Y-180956D01*
X391964Y-180267D01*
X391275Y-179807D01*
X390462Y-179645D01*
D02*
G37*
G36*
X311722D02*
X310909Y-179807D01*
X310220Y-180267D01*
X309760Y-180956D01*
X309598Y-181769D01*
X309760Y-182582D01*
X310220Y-183271D01*
X310909Y-183731D01*
X311722Y-183893D01*
X312535Y-183731D01*
X313224Y-183271D01*
X313684Y-182582D01*
X313846Y-181769D01*
X313684Y-180956D01*
X313224Y-180267D01*
X312535Y-179807D01*
X311722Y-179645D01*
D02*
G37*
G36*
X453193Y-170117D02*
X451839Y-170251D01*
X450537Y-170646D01*
X449338Y-171287D01*
X448286Y-172150D01*
X447423Y-173201D01*
X446782Y-174401D01*
X446387Y-175703D01*
X446254Y-177056D01*
X446387Y-178410D01*
X446782Y-179712D01*
X447423Y-180912D01*
X448286Y-181963D01*
X449338Y-182826D01*
X450537Y-183467D01*
X451839Y-183862D01*
X453193Y-183995D01*
X454546Y-183862D01*
X455848Y-183467D01*
X457048Y-182826D01*
X458099Y-181963D01*
X458962Y-180912D01*
X459604Y-179712D01*
X459998Y-178410D01*
X460132Y-177056D01*
X459998Y-175703D01*
X459604Y-174401D01*
X458962Y-173201D01*
X458099Y-172150D01*
X457048Y-171287D01*
X455848Y-170646D01*
X454546Y-170251D01*
X453193Y-170117D01*
D02*
G37*
G36*
X256593D02*
X255239Y-170251D01*
X253937Y-170646D01*
X252738Y-171287D01*
X251686Y-172150D01*
X250823Y-173201D01*
X250182Y-174401D01*
X249787Y-175703D01*
X249654Y-177056D01*
X249787Y-178410D01*
X250182Y-179712D01*
X250823Y-180912D01*
X251686Y-181963D01*
X252738Y-182826D01*
X253937Y-183467D01*
X255239Y-183862D01*
X256593Y-183995D01*
X257946Y-183862D01*
X259248Y-183467D01*
X260448Y-182826D01*
X261499Y-181963D01*
X262362Y-180912D01*
X263003Y-179712D01*
X263398Y-178410D01*
X263532Y-177056D01*
X263398Y-175703D01*
X263003Y-174401D01*
X262362Y-173201D01*
X261499Y-172150D01*
X260448Y-171287D01*
X259248Y-170646D01*
X257946Y-170251D01*
X256593Y-170117D01*
D02*
G37*
G36*
X35827Y-183920D02*
X35124Y-184060D01*
X34834Y-184254D01*
X34449Y-184422D01*
X34064Y-184254D01*
X33773Y-184060D01*
X33071Y-183920D01*
X32368Y-184060D01*
X31773Y-184457D01*
X31375Y-185053D01*
X31236Y-185755D01*
X31375Y-186457D01*
X31773Y-187053D01*
X32368Y-187451D01*
X33071Y-187590D01*
X33773Y-187451D01*
X34064Y-187257D01*
X34449Y-187088D01*
X34834Y-187257D01*
X35124Y-187451D01*
X35827Y-187590D01*
X36529Y-187451D01*
X37124Y-187053D01*
X37522Y-186457D01*
X37662Y-185755D01*
X37522Y-185053D01*
X37124Y-184457D01*
X36529Y-184060D01*
X35827Y-183920D01*
D02*
G37*
G36*
X381890Y-182023D02*
X381187Y-182163D01*
X380592Y-182561D01*
X380194Y-183156D01*
X380054Y-183858D01*
X380194Y-184561D01*
X380592Y-185156D01*
X381187Y-185554D01*
X381890Y-185694D01*
X382592Y-185554D01*
X383117Y-185203D01*
X383348Y-185550D01*
X383943Y-185948D01*
X384646Y-186087D01*
X385348Y-185948D01*
X385943Y-185550D01*
X386341Y-184954D01*
X386481Y-184252D01*
X386341Y-183550D01*
X385943Y-182954D01*
X385348Y-182556D01*
X384646Y-182417D01*
X383943Y-182556D01*
X383419Y-182907D01*
X383188Y-182561D01*
X382592Y-182163D01*
X381890Y-182023D01*
D02*
G37*
G36*
X275590Y-182417D02*
X274888Y-182556D01*
X274293Y-182954D01*
X273895Y-183550D01*
X273755Y-184252D01*
X273895Y-184954D01*
X274293Y-185550D01*
X274888Y-185948D01*
X275590Y-186087D01*
X276293Y-185948D01*
X276888Y-185550D01*
X277286Y-184954D01*
X277426Y-184252D01*
X277286Y-183550D01*
X276888Y-182954D01*
X276293Y-182556D01*
X275590Y-182417D01*
D02*
G37*
G36*
X299606Y-183598D02*
X298904Y-183738D01*
X298309Y-184135D01*
X297911Y-184731D01*
X297771Y-185433D01*
X297911Y-186135D01*
X298309Y-186731D01*
X298904Y-187129D01*
X299606Y-187268D01*
X300309Y-187129D01*
X300904Y-186731D01*
X301302Y-186135D01*
X301442Y-185433D01*
X301302Y-184731D01*
X300904Y-184135D01*
X300309Y-183738D01*
X299606Y-183598D01*
D02*
G37*
G36*
X9843Y-183920D02*
X9140Y-184060D01*
X8545Y-184457D01*
X8147Y-185053D01*
X8007Y-185755D01*
X8147Y-186457D01*
X8545Y-187053D01*
X9140Y-187451D01*
X9843Y-187590D01*
X10545Y-187451D01*
X11140Y-187053D01*
X11538Y-186457D01*
X11678Y-185755D01*
X11538Y-185053D01*
X11140Y-184457D01*
X10545Y-184060D01*
X9843Y-183920D01*
D02*
G37*
G36*
X611614Y-184272D02*
X610912Y-184412D01*
X610316Y-184810D01*
X609919Y-185405D01*
X609779Y-186107D01*
X609919Y-186810D01*
X610316Y-187405D01*
X610912Y-187803D01*
X611614Y-187943D01*
X612317Y-187803D01*
X612912Y-187405D01*
X613310Y-186810D01*
X613449Y-186107D01*
X613310Y-185405D01*
X612912Y-184810D01*
X612317Y-184412D01*
X611614Y-184272D01*
D02*
G37*
G36*
X561024Y-181629D02*
X560321Y-181769D01*
X559726Y-182167D01*
X559328Y-182762D01*
X559188Y-183465D01*
X559328Y-184167D01*
X559704Y-184730D01*
X559766Y-184876D01*
Y-185202D01*
X559704Y-185349D01*
X559328Y-185912D01*
X559188Y-186614D01*
X559328Y-187317D01*
X559726Y-187912D01*
X560321Y-188310D01*
X561024Y-188449D01*
X561726Y-188310D01*
X562321Y-187912D01*
X562719Y-187317D01*
X562859Y-186614D01*
X562719Y-185912D01*
X562343Y-185349D01*
X562281Y-185202D01*
Y-184876D01*
X562343Y-184730D01*
X562719Y-184167D01*
X562859Y-183465D01*
X562719Y-182762D01*
X562321Y-182167D01*
X561726Y-181769D01*
X561024Y-181629D01*
D02*
G37*
G36*
X292815Y-185271D02*
X292113Y-185411D01*
X291517Y-185809D01*
X291119Y-186404D01*
X290980Y-187106D01*
X291119Y-187809D01*
X291517Y-188404D01*
X292113Y-188802D01*
X292815Y-188942D01*
X293517Y-188802D01*
X294113Y-188404D01*
X294511Y-187809D01*
X294650Y-187106D01*
X294511Y-186404D01*
X294113Y-185809D01*
X293517Y-185411D01*
X292815Y-185271D01*
D02*
G37*
G36*
X-23622Y-175330D02*
X-24324Y-175470D01*
X-24920Y-175868D01*
X-25318Y-176463D01*
X-25457Y-177165D01*
X-25318Y-177868D01*
X-24920Y-178463D01*
X-24324Y-178861D01*
X-24234Y-178879D01*
Y-179389D01*
X-24324Y-179407D01*
X-24920Y-179805D01*
X-25318Y-180400D01*
X-25457Y-181102D01*
X-25318Y-181805D01*
X-25032Y-182231D01*
X-24958Y-182579D01*
X-25032Y-182926D01*
X-25318Y-183353D01*
X-25457Y-184055D01*
X-25318Y-184757D01*
X-24920Y-185353D01*
X-24324Y-185751D01*
X-24234Y-185769D01*
Y-186278D01*
X-24324Y-186297D01*
X-24920Y-186694D01*
X-25318Y-187290D01*
X-25457Y-187992D01*
X-25318Y-188695D01*
X-24920Y-189290D01*
X-24324Y-189688D01*
X-23622Y-189827D01*
X-22920Y-189688D01*
X-22324Y-189290D01*
X-21926Y-188695D01*
X-21787Y-187992D01*
X-21926Y-187290D01*
X-22324Y-186694D01*
X-22920Y-186297D01*
X-23010Y-186278D01*
Y-185769D01*
X-22920Y-185751D01*
X-22324Y-185353D01*
X-21926Y-184757D01*
X-21787Y-184055D01*
X-21926Y-183353D01*
X-22212Y-182926D01*
X-22286Y-182579D01*
X-22212Y-182231D01*
X-21926Y-181805D01*
X-21787Y-181102D01*
X-21926Y-180400D01*
X-22324Y-179805D01*
X-22920Y-179407D01*
X-23010Y-179389D01*
Y-178879D01*
X-22920Y-178861D01*
X-22324Y-178463D01*
X-21926Y-177868D01*
X-21787Y-177165D01*
X-21926Y-176463D01*
X-22324Y-175868D01*
X-22920Y-175470D01*
X-23622Y-175330D01*
D02*
G37*
G36*
X281890Y-186747D02*
X281187Y-186887D01*
X280592Y-187285D01*
X280194Y-187880D01*
X280054Y-188583D01*
X280194Y-189285D01*
X280592Y-189880D01*
X281187Y-190278D01*
X281890Y-190418D01*
X282592Y-190278D01*
X283188Y-189880D01*
X283585Y-189285D01*
X283725Y-188583D01*
X283585Y-187880D01*
X283188Y-187285D01*
X282592Y-186887D01*
X281890Y-186747D01*
D02*
G37*
G36*
X274803D02*
X274101Y-186887D01*
X273505Y-187285D01*
X273108Y-187880D01*
X272968Y-188583D01*
X273108Y-189285D01*
X273505Y-189880D01*
X274101Y-190278D01*
X274803Y-190418D01*
X275505Y-190278D01*
X276101Y-189880D01*
X276499Y-189285D01*
X276638Y-188583D01*
X276499Y-187880D01*
X276101Y-187285D01*
X275505Y-186887D01*
X274803Y-186747D01*
D02*
G37*
G36*
X591339Y-187928D02*
X590636Y-188068D01*
X590041Y-188466D01*
X589643Y-189061D01*
X589503Y-189764D01*
X589643Y-190466D01*
X590041Y-191061D01*
X590636Y-191459D01*
X591339Y-191599D01*
X592041Y-191459D01*
X592636Y-191061D01*
X593034Y-190466D01*
X593174Y-189764D01*
X593034Y-189061D01*
X592636Y-188466D01*
X592041Y-188068D01*
X591339Y-187928D01*
D02*
G37*
G36*
X30709Y-188576D02*
X30006Y-188716D01*
X29411Y-189113D01*
X29013Y-189709D01*
X28873Y-190411D01*
X29013Y-191113D01*
X29411Y-191709D01*
X30006Y-192107D01*
X30709Y-192246D01*
X31411Y-192107D01*
X32006Y-191709D01*
X32404Y-191113D01*
X32544Y-190411D01*
X32404Y-189709D01*
X32006Y-189113D01*
X31411Y-188716D01*
X30709Y-188576D01*
D02*
G37*
G36*
X13780Y-188716D02*
X13077Y-188856D01*
X12482Y-189253D01*
X12084Y-189849D01*
X11944Y-190551D01*
X12084Y-191253D01*
X12482Y-191849D01*
X13077Y-192247D01*
X13780Y-192386D01*
X14482Y-192247D01*
X15077Y-191849D01*
X15475Y-191253D01*
X15615Y-190551D01*
X15475Y-189849D01*
X15077Y-189253D01*
X14482Y-188856D01*
X13780Y-188716D01*
D02*
G37*
G36*
X295669Y-189503D02*
X294967Y-189643D01*
X294372Y-190041D01*
X293974Y-190636D01*
X293834Y-191339D01*
X293974Y-192041D01*
X294372Y-192636D01*
X294967Y-193034D01*
X295669Y-193174D01*
X296372Y-193034D01*
X296967Y-192636D01*
X297365Y-192041D01*
X297505Y-191339D01*
X297365Y-190636D01*
X296967Y-190041D01*
X296372Y-189643D01*
X295669Y-189503D01*
D02*
G37*
G36*
X19682Y-190684D02*
X18980Y-190824D01*
X18384Y-191222D01*
X17986Y-191817D01*
X17846Y-192520D01*
X17986Y-193222D01*
X18384Y-193817D01*
X18980Y-194215D01*
X19682Y-194355D01*
X20384Y-194215D01*
X20979Y-193817D01*
X21377Y-193222D01*
X21517Y-192520D01*
X21377Y-191817D01*
X20979Y-191222D01*
X20384Y-190824D01*
X19682Y-190684D01*
D02*
G37*
G36*
X583858Y-191078D02*
X583156Y-191218D01*
X582560Y-191616D01*
X582163Y-192211D01*
X582023Y-192913D01*
X582163Y-193616D01*
X582560Y-194211D01*
X583156Y-194609D01*
X583858Y-194749D01*
X584561Y-194609D01*
X585156Y-194211D01*
X585554Y-193616D01*
X585694Y-192913D01*
X585554Y-192211D01*
X585156Y-191616D01*
X584561Y-191218D01*
X583858Y-191078D01*
D02*
G37*
G36*
X399213Y-191472D02*
X398510Y-191612D01*
X397915Y-192009D01*
X397517Y-192605D01*
X397377Y-193307D01*
X397517Y-194009D01*
X397915Y-194605D01*
X398510Y-195003D01*
X399213Y-195142D01*
X399915Y-195003D01*
X400510Y-194605D01*
X400908Y-194009D01*
X401048Y-193307D01*
X400908Y-192605D01*
X400510Y-192009D01*
X399915Y-191612D01*
X399213Y-191472D01*
D02*
G37*
G36*
X322835Y-194228D02*
X322132Y-194367D01*
X321537Y-194765D01*
X321139Y-195361D01*
X321121Y-195449D01*
X320591Y-195555D01*
X320589Y-195553D01*
X319994Y-195155D01*
X319291Y-195015D01*
X318589Y-195155D01*
X317994Y-195553D01*
X317596Y-196148D01*
X317456Y-196850D01*
X317596Y-197553D01*
X317994Y-198148D01*
X318589Y-198546D01*
X319291Y-198686D01*
X319994Y-198546D01*
X320589Y-198148D01*
X320987Y-197553D01*
X321005Y-197464D01*
X321535Y-197358D01*
X321537Y-197361D01*
X322132Y-197758D01*
X322835Y-197898D01*
X323537Y-197758D01*
X324132Y-197361D01*
X324530Y-196765D01*
X324670Y-196063D01*
X324530Y-195361D01*
X324132Y-194765D01*
X323537Y-194367D01*
X322835Y-194228D01*
D02*
G37*
G36*
X341774Y-194491D02*
X341071Y-194631D01*
X340476Y-195028D01*
X340078Y-195624D01*
X340012Y-195954D01*
X339503D01*
X339469Y-195787D01*
X339071Y-195192D01*
X338476Y-194794D01*
X337774Y-194654D01*
X337071Y-194794D01*
X336476Y-195192D01*
X336078Y-195787D01*
X335938Y-196489D01*
X336078Y-197192D01*
X336476Y-197787D01*
X337071Y-198185D01*
X337774Y-198325D01*
X338476Y-198185D01*
X339071Y-197787D01*
X339469Y-197192D01*
X339535Y-196861D01*
X340045D01*
X340078Y-197028D01*
X340476Y-197624D01*
X341071Y-198022D01*
X341774Y-198161D01*
X342476Y-198022D01*
X343071Y-197624D01*
X343469Y-197028D01*
X343609Y-196326D01*
X343469Y-195624D01*
X343071Y-195028D01*
X342476Y-194631D01*
X341774Y-194491D01*
D02*
G37*
G36*
X309055Y-193834D02*
X308353Y-193974D01*
X307757Y-194372D01*
X307360Y-194967D01*
X307220Y-195669D01*
X307360Y-196372D01*
X307480Y-196552D01*
X307179Y-197002D01*
X307087Y-196984D01*
X306384Y-197123D01*
X305789Y-197521D01*
X305391Y-198117D01*
X305251Y-198819D01*
X305391Y-199521D01*
X305789Y-200117D01*
X306384Y-200515D01*
X307087Y-200654D01*
X307789Y-200515D01*
X308384Y-200117D01*
X308782Y-199521D01*
X308922Y-198819D01*
X308782Y-198117D01*
X308662Y-197936D01*
X308962Y-197486D01*
X309055Y-197504D01*
X309757Y-197365D01*
X310353Y-196967D01*
X310751Y-196372D01*
X310890Y-195669D01*
X310751Y-194967D01*
X310353Y-194372D01*
X309757Y-193974D01*
X309055Y-193834D01*
D02*
G37*
G36*
X331220Y-194431D02*
X330518Y-194571D01*
X329922Y-194969D01*
X329525Y-195564D01*
X329385Y-196266D01*
X329525Y-196969D01*
X329922Y-197564D01*
X330518Y-197962D01*
X331220Y-198102D01*
X331923Y-197962D01*
X332518Y-197564D01*
X332916Y-196969D01*
X333055Y-196266D01*
X332916Y-195564D01*
X332518Y-194969D01*
X331923Y-194571D01*
X331220Y-194431D01*
D02*
G37*
G36*
X389567Y-194604D02*
X388865Y-194744D01*
X388269Y-195142D01*
X387872Y-195737D01*
X387732Y-196440D01*
X387872Y-197142D01*
X388269Y-197737D01*
X388865Y-198135D01*
X389567Y-198275D01*
X390269Y-198135D01*
X390865Y-197737D01*
X391263Y-197142D01*
X391403Y-196440D01*
X391263Y-195737D01*
X390865Y-195142D01*
X390269Y-194744D01*
X389567Y-194604D01*
D02*
G37*
G36*
X380363Y-194905D02*
X379661Y-195045D01*
X379066Y-195442D01*
X378668Y-196038D01*
X378528Y-196740D01*
X378668Y-197442D01*
X379066Y-198038D01*
X379661Y-198436D01*
X380363Y-198575D01*
X381066Y-198436D01*
X381661Y-198038D01*
X382059Y-197442D01*
X382199Y-196740D01*
X382059Y-196038D01*
X381661Y-195442D01*
X381066Y-195045D01*
X380363Y-194905D01*
D02*
G37*
G36*
X291831Y-195177D02*
X291128Y-195317D01*
X290533Y-195715D01*
X290135Y-196310D01*
X289995Y-197012D01*
X290135Y-197715D01*
X290533Y-198310D01*
X291128Y-198708D01*
X291831Y-198848D01*
X292533Y-198708D01*
X293128Y-198310D01*
X293526Y-197715D01*
X293666Y-197012D01*
X293526Y-196310D01*
X293128Y-195715D01*
X292533Y-195317D01*
X291831Y-195177D01*
D02*
G37*
G36*
X481496Y-195409D02*
X480794Y-195548D01*
X480198Y-195946D01*
X479801Y-196542D01*
X479661Y-197244D01*
X479801Y-197946D01*
X480198Y-198542D01*
X480794Y-198940D01*
X481496Y-199079D01*
X482198Y-198940D01*
X482794Y-198542D01*
X483192Y-197946D01*
X483331Y-197244D01*
X483192Y-196542D01*
X482794Y-195946D01*
X482198Y-195548D01*
X481496Y-195409D01*
D02*
G37*
G36*
X362598D02*
X361896Y-195548D01*
X361301Y-195946D01*
X360903Y-196542D01*
X360763Y-197244D01*
X360903Y-197946D01*
X361301Y-198542D01*
X361896Y-198940D01*
X362598Y-199079D01*
X363301Y-198940D01*
X363896Y-198542D01*
X364294Y-197946D01*
X364434Y-197244D01*
X364294Y-196542D01*
X363896Y-195946D01*
X363301Y-195548D01*
X362598Y-195409D01*
D02*
G37*
G36*
X394193Y-195835D02*
X393491Y-195975D01*
X392896Y-196373D01*
X392498Y-196968D01*
X392358Y-197670D01*
X392498Y-198373D01*
X392896Y-198968D01*
X393491Y-199366D01*
X394193Y-199506D01*
X394896Y-199366D01*
X395491Y-198968D01*
X395889Y-198373D01*
X396028Y-197670D01*
X395889Y-196968D01*
X395491Y-196373D01*
X394896Y-195975D01*
X394193Y-195835D01*
D02*
G37*
G36*
X375698Y-195865D02*
X374996Y-196004D01*
X374400Y-196402D01*
X374002Y-196998D01*
X373863Y-197700D01*
X374002Y-198402D01*
X374400Y-198998D01*
X374996Y-199396D01*
X375698Y-199535D01*
X376400Y-199396D01*
X376996Y-198998D01*
X377394Y-198402D01*
X377533Y-197700D01*
X377394Y-196998D01*
X376996Y-196402D01*
X376400Y-196004D01*
X375698Y-195865D01*
D02*
G37*
G36*
X521654Y-196984D02*
X520951Y-197123D01*
X520356Y-197521D01*
X519958Y-198117D01*
X519818Y-198819D01*
X519958Y-199521D01*
X520356Y-200117D01*
X520951Y-200515D01*
X521654Y-200654D01*
X522356Y-200515D01*
X522951Y-200117D01*
X523349Y-199521D01*
X523489Y-198819D01*
X523349Y-198117D01*
X522951Y-197521D01*
X522356Y-197123D01*
X521654Y-196984D01*
D02*
G37*
G36*
X314675D02*
X313973Y-197123D01*
X313377Y-197521D01*
X312979Y-198117D01*
X312840Y-198819D01*
X312979Y-199521D01*
X313377Y-200117D01*
X313973Y-200515D01*
X314675Y-200654D01*
X315377Y-200515D01*
X315973Y-200117D01*
X316371Y-199521D01*
X316510Y-198819D01*
X316371Y-198117D01*
X315973Y-197521D01*
X315377Y-197123D01*
X314675Y-196984D01*
D02*
G37*
G36*
X513386Y-197377D02*
X512683Y-197517D01*
X512088Y-197915D01*
X511690Y-198510D01*
X511551Y-199213D01*
X511690Y-199915D01*
X512088Y-200510D01*
X512683Y-200908D01*
X513386Y-201048D01*
X514088Y-200908D01*
X514684Y-200510D01*
X515081Y-199915D01*
X515221Y-199213D01*
X515081Y-198510D01*
X514684Y-197915D01*
X514088Y-197517D01*
X513386Y-197377D01*
D02*
G37*
G36*
X275590Y-197771D02*
X274888Y-197911D01*
X274293Y-198309D01*
X273895Y-198904D01*
X273755Y-199606D01*
X273895Y-200309D01*
X274293Y-200904D01*
X274888Y-201302D01*
X275590Y-201442D01*
X276293Y-201302D01*
X276888Y-200904D01*
X277286Y-200309D01*
X277426Y-199606D01*
X277286Y-198904D01*
X276888Y-198309D01*
X276293Y-197911D01*
X275590Y-197771D01*
D02*
G37*
G36*
X343701Y-198558D02*
X342999Y-198698D01*
X342403Y-199096D01*
X342005Y-199691D01*
X341865Y-200394D01*
X342005Y-201096D01*
X342403Y-201691D01*
X342999Y-202089D01*
X343701Y-202229D01*
X344403Y-202089D01*
X344999Y-201691D01*
X345396Y-201096D01*
X345536Y-200394D01*
X345396Y-199691D01*
X344999Y-199096D01*
X344403Y-198698D01*
X343701Y-198558D01*
D02*
G37*
G36*
X289370D02*
X288668Y-198698D01*
X288072Y-199096D01*
X287674Y-199691D01*
X287535Y-200394D01*
X287674Y-201096D01*
X288072Y-201691D01*
X288668Y-202089D01*
X289370Y-202229D01*
X290072Y-202089D01*
X290668Y-201691D01*
X291066Y-201096D01*
X291205Y-200394D01*
X291066Y-199691D01*
X290668Y-199096D01*
X290072Y-198698D01*
X289370Y-198558D01*
D02*
G37*
G36*
X261024D02*
X260321Y-198698D01*
X259726Y-199096D01*
X259328Y-199691D01*
X259188Y-200394D01*
X259328Y-201096D01*
X259726Y-201691D01*
X260321Y-202089D01*
X261024Y-202229D01*
X261726Y-202089D01*
X262321Y-201691D01*
X262719Y-201096D01*
X262859Y-200394D01*
X262719Y-199691D01*
X262321Y-199096D01*
X261726Y-198698D01*
X261024Y-198558D01*
D02*
G37*
G36*
X589370Y-199740D02*
X588668Y-199879D01*
X588072Y-200277D01*
X587675Y-200872D01*
X587535Y-201575D01*
X587675Y-202277D01*
X588072Y-202872D01*
X588668Y-203270D01*
X589370Y-203410D01*
X590072Y-203270D01*
X590668Y-202872D01*
X591066Y-202277D01*
X591205Y-201575D01*
X591066Y-200872D01*
X590668Y-200277D01*
X590072Y-199879D01*
X589370Y-199740D01*
D02*
G37*
G36*
X385541Y-200625D02*
X384839Y-200765D01*
X384243Y-201163D01*
X383845Y-201758D01*
X383706Y-202460D01*
X383845Y-203163D01*
X384243Y-203758D01*
X384839Y-204156D01*
X385541Y-204295D01*
X386243Y-204156D01*
X386839Y-203758D01*
X387237Y-203163D01*
X387376Y-202460D01*
X387237Y-201758D01*
X386839Y-201163D01*
X386243Y-200765D01*
X385541Y-200625D01*
D02*
G37*
G36*
X347638Y-200921D02*
X346936Y-201060D01*
X346340Y-201458D01*
X345942Y-202054D01*
X345802Y-202756D01*
X345942Y-203458D01*
X346340Y-204054D01*
X346936Y-204451D01*
X347638Y-204591D01*
X348340Y-204451D01*
X348936Y-204054D01*
X349333Y-203458D01*
X349473Y-202756D01*
X349333Y-202054D01*
X348936Y-201458D01*
X348340Y-201060D01*
X347638Y-200921D01*
D02*
G37*
G36*
X373730Y-201053D02*
X373028Y-201193D01*
X372432Y-201591D01*
X372035Y-202186D01*
X371895Y-202888D01*
X372035Y-203591D01*
X372432Y-204186D01*
X373028Y-204584D01*
X373730Y-204724D01*
X374432Y-204584D01*
X375028Y-204186D01*
X375426Y-203591D01*
X375565Y-202888D01*
X375426Y-202186D01*
X375028Y-201591D01*
X374432Y-201193D01*
X373730Y-201053D01*
D02*
G37*
G36*
X289370Y-204070D02*
X288668Y-204210D01*
X288072Y-204608D01*
X287674Y-205203D01*
X287535Y-205906D01*
X287674Y-206608D01*
X288072Y-207203D01*
X288668Y-207601D01*
X289370Y-207741D01*
X290072Y-207601D01*
X290668Y-207203D01*
X291066Y-206608D01*
X291205Y-205906D01*
X291066Y-205203D01*
X290668Y-204608D01*
X290072Y-204210D01*
X289370Y-204070D01*
D02*
G37*
G36*
X383572Y-204369D02*
X382870Y-204509D01*
X382274Y-204907D01*
X381876Y-205502D01*
X381737Y-206205D01*
X381876Y-206907D01*
X382274Y-207502D01*
X382870Y-207900D01*
X383572Y-208040D01*
X384274Y-207900D01*
X384870Y-207502D01*
X385268Y-206907D01*
X385407Y-206205D01*
X385268Y-205502D01*
X384870Y-204907D01*
X384274Y-204509D01*
X383572Y-204369D01*
D02*
G37*
G36*
X424409Y-203677D02*
X423707Y-203816D01*
X423112Y-204214D01*
X422714Y-204809D01*
X422574Y-205512D01*
X422714Y-206214D01*
X423112Y-206809D01*
X423707Y-207207D01*
X424409Y-207347D01*
X425112Y-207207D01*
X425707Y-206809D01*
X425709Y-206807D01*
X426239Y-206913D01*
X426257Y-207001D01*
X426655Y-207597D01*
X427250Y-207995D01*
X427953Y-208135D01*
X428655Y-207995D01*
X429250Y-207597D01*
X429648Y-207001D01*
X429788Y-206299D01*
X429648Y-205597D01*
X429250Y-205001D01*
X428655Y-204604D01*
X427953Y-204464D01*
X427250Y-204604D01*
X426655Y-205001D01*
X426653Y-205004D01*
X426123Y-204898D01*
X426105Y-204809D01*
X425707Y-204214D01*
X425112Y-203816D01*
X424409Y-203677D01*
D02*
G37*
G36*
X588922Y-204627D02*
X588220Y-204766D01*
X587625Y-205164D01*
X587227Y-205760D01*
X587087Y-206462D01*
X587227Y-207164D01*
X587625Y-207760D01*
X588220Y-208157D01*
X588922Y-208297D01*
X589625Y-208157D01*
X590220Y-207760D01*
X590618Y-207164D01*
X590758Y-206462D01*
X590618Y-205760D01*
X590220Y-205164D01*
X589625Y-204766D01*
X588922Y-204627D01*
D02*
G37*
G36*
X343701Y-207614D02*
X342999Y-207753D01*
X342403Y-208151D01*
X342005Y-208747D01*
X341865Y-209449D01*
X342005Y-210151D01*
X342403Y-210747D01*
X342999Y-211144D01*
X343701Y-211284D01*
X344403Y-211144D01*
X344999Y-210747D01*
X345396Y-210151D01*
X345536Y-209449D01*
X345396Y-208747D01*
X344999Y-208151D01*
X344403Y-207753D01*
X343701Y-207614D01*
D02*
G37*
G36*
X309449Y-209976D02*
X308747Y-210116D01*
X308151Y-210513D01*
X307753Y-211109D01*
X307614Y-211811D01*
X307753Y-212513D01*
X308151Y-213109D01*
X308747Y-213507D01*
X309449Y-213646D01*
X310151Y-213507D01*
X310747Y-213109D01*
X311076Y-212615D01*
X311575Y-212719D01*
X311690Y-213301D01*
X312088Y-213896D01*
X312684Y-214294D01*
X313386Y-214434D01*
X314088Y-214294D01*
X314684Y-213896D01*
X315081Y-213301D01*
X315221Y-212598D01*
X315081Y-211896D01*
X314684Y-211301D01*
X314088Y-210903D01*
X313386Y-210763D01*
X312684Y-210903D01*
X312088Y-211301D01*
X311758Y-211794D01*
X311260Y-211691D01*
X311144Y-211109D01*
X310747Y-210513D01*
X310151Y-210116D01*
X309449Y-209976D01*
D02*
G37*
G36*
X589370Y-211157D02*
X588668Y-211297D01*
X588072Y-211694D01*
X587675Y-212290D01*
X587535Y-212992D01*
X587675Y-213695D01*
X588072Y-214290D01*
X588668Y-214688D01*
X589370Y-214827D01*
X590072Y-214688D01*
X590668Y-214290D01*
X591066Y-213695D01*
X591205Y-212992D01*
X591066Y-212290D01*
X590668Y-211694D01*
X590072Y-211297D01*
X589370Y-211157D01*
D02*
G37*
G36*
X-3528Y-205543D02*
X-13402D01*
Y-215417D01*
X-3528D01*
Y-205543D01*
D02*
G37*
G36*
X579134Y-212171D02*
X578432Y-212310D01*
X577836Y-212708D01*
X577438Y-213304D01*
X577299Y-214006D01*
X577438Y-214708D01*
X577836Y-215304D01*
X578432Y-215702D01*
X579134Y-215841D01*
X579836Y-215702D01*
X580432Y-215304D01*
X580829Y-214708D01*
X580969Y-214006D01*
X580829Y-213304D01*
X580432Y-212708D01*
X579836Y-212310D01*
X579134Y-212171D01*
D02*
G37*
G36*
X357480Y-212732D02*
X356778Y-212871D01*
X356183Y-213269D01*
X355785Y-213865D01*
X355645Y-214567D01*
X355785Y-215269D01*
X356183Y-215865D01*
X356778Y-216263D01*
X357480Y-216402D01*
X358183Y-216263D01*
X358778Y-215865D01*
X359176Y-215269D01*
X359316Y-214567D01*
X359176Y-213865D01*
X358778Y-213269D01*
X358183Y-212871D01*
X357480Y-212732D01*
D02*
G37*
G36*
X261082Y-213839D02*
X260269Y-214000D01*
X259580Y-214461D01*
X259120Y-215150D01*
X258958Y-215962D01*
X259120Y-216775D01*
X259580Y-217464D01*
X260269Y-217925D01*
X261082Y-218086D01*
X261894Y-217925D01*
X262584Y-217464D01*
X263044Y-216775D01*
X263206Y-215962D01*
X263044Y-215150D01*
X262584Y-214461D01*
X261894Y-214000D01*
X261082Y-213839D01*
D02*
G37*
G36*
X448573Y-213848D02*
X447760Y-214010D01*
X447071Y-214470D01*
X446611Y-215159D01*
X446449Y-215972D01*
X446611Y-216785D01*
X447071Y-217474D01*
X447760Y-217934D01*
X448573Y-218096D01*
X449385Y-217934D01*
X450074Y-217474D01*
X450535Y-216785D01*
X450697Y-215972D01*
X450535Y-215159D01*
X450074Y-214470D01*
X449385Y-214010D01*
X448573Y-213848D01*
D02*
G37*
G36*
X488189Y-214700D02*
X487487Y-214840D01*
X486891Y-215238D01*
X486493Y-215833D01*
X486354Y-216535D01*
X486493Y-217238D01*
X486891Y-217833D01*
X487487Y-218231D01*
X488189Y-218371D01*
X488891Y-218231D01*
X489487Y-217833D01*
X489885Y-217238D01*
X490024Y-216535D01*
X489885Y-215833D01*
X489487Y-215238D01*
X488891Y-214840D01*
X488189Y-214700D01*
D02*
G37*
G36*
X407874D02*
X407172Y-214840D01*
X406576Y-215238D01*
X406179Y-215833D01*
X406039Y-216535D01*
X406179Y-217238D01*
X406576Y-217833D01*
X407172Y-218231D01*
X407874Y-218371D01*
X408576Y-218231D01*
X409172Y-217833D01*
X409570Y-217238D01*
X409709Y-216535D01*
X409570Y-215833D01*
X409172Y-215238D01*
X408576Y-214840D01*
X407874Y-214700D01*
D02*
G37*
G36*
X390158Y-215881D02*
X389455Y-216021D01*
X388860Y-216419D01*
X388462Y-217014D01*
X388322Y-217717D01*
X388462Y-218419D01*
X388860Y-219014D01*
X389455Y-219412D01*
X390158Y-219552D01*
X390860Y-219412D01*
X391455Y-219014D01*
X391853Y-218419D01*
X391993Y-217717D01*
X391853Y-217014D01*
X391455Y-216419D01*
X390860Y-216021D01*
X390158Y-215881D01*
D02*
G37*
G36*
X368232D02*
X367529Y-216021D01*
X366934Y-216419D01*
X366536Y-217014D01*
X366396Y-217717D01*
X366536Y-218419D01*
X366934Y-219014D01*
X367529Y-219412D01*
X368232Y-219552D01*
X368934Y-219412D01*
X369530Y-219014D01*
X369927Y-218419D01*
X370067Y-217717D01*
X369927Y-217014D01*
X369530Y-216419D01*
X368934Y-216021D01*
X368232Y-215881D01*
D02*
G37*
G36*
X404626Y-217850D02*
X403924Y-217989D01*
X403328Y-218387D01*
X402930Y-218983D01*
X402791Y-219685D01*
X402930Y-220387D01*
X403328Y-220983D01*
X403924Y-221381D01*
X404626Y-221520D01*
X405328Y-221381D01*
X405924Y-220983D01*
X406321Y-220387D01*
X406461Y-219685D01*
X406321Y-218983D01*
X405924Y-218387D01*
X405328Y-217989D01*
X404626Y-217850D01*
D02*
G37*
G36*
X500971Y-218060D02*
X500268Y-218200D01*
X499673Y-218598D01*
X499275Y-219193D01*
X499135Y-219896D01*
X499275Y-220598D01*
X499673Y-221193D01*
X500268Y-221591D01*
X500971Y-221731D01*
X501673Y-221591D01*
X502268Y-221193D01*
X502666Y-220598D01*
X502806Y-219896D01*
X502666Y-219193D01*
X502268Y-218598D01*
X501673Y-218200D01*
X500971Y-218060D01*
D02*
G37*
G36*
X590188Y-219326D02*
X589486Y-219466D01*
X588890Y-219864D01*
X588493Y-220459D01*
X588353Y-221161D01*
X588493Y-221864D01*
X588890Y-222459D01*
X589486Y-222857D01*
X590188Y-222997D01*
X590890Y-222857D01*
X591486Y-222459D01*
X591884Y-221864D01*
X592023Y-221161D01*
X591884Y-220459D01*
X591486Y-219864D01*
X590890Y-219466D01*
X590188Y-219326D01*
D02*
G37*
G36*
X608661Y-218637D02*
X607959Y-218777D01*
X607364Y-219175D01*
X606966Y-219770D01*
X606826Y-220472D01*
X606966Y-221175D01*
X607364Y-221770D01*
X607959Y-222168D01*
X608661Y-222308D01*
X609364Y-222168D01*
X609613Y-222001D01*
X610103Y-221963D01*
X610235Y-222141D01*
X610513Y-222558D01*
X611109Y-222955D01*
X611811Y-223095D01*
X612513Y-222955D01*
X613109Y-222558D01*
X613507Y-221962D01*
X613646Y-221260D01*
X613507Y-220557D01*
X613109Y-219962D01*
X612513Y-219564D01*
X611811Y-219425D01*
X611109Y-219564D01*
X610859Y-219731D01*
X610370Y-219769D01*
X610237Y-219591D01*
X609959Y-219175D01*
X609364Y-218777D01*
X608661Y-218637D01*
D02*
G37*
G36*
X375197Y-219425D02*
X374495Y-219564D01*
X373899Y-219962D01*
X373501Y-220557D01*
X373362Y-221260D01*
X373501Y-221962D01*
X373899Y-222558D01*
X374495Y-222955D01*
X375197Y-223095D01*
X375899Y-222955D01*
X376495Y-222558D01*
X376892Y-221962D01*
X377032Y-221260D01*
X376892Y-220557D01*
X376495Y-219962D01*
X375899Y-219564D01*
X375197Y-219425D01*
D02*
G37*
G36*
X382776Y-219720D02*
X382073Y-219860D01*
X381478Y-220257D01*
X381080Y-220853D01*
X380940Y-221555D01*
X381080Y-222257D01*
X381478Y-222853D01*
X382073Y-223251D01*
X382776Y-223390D01*
X383478Y-223251D01*
X384073Y-222853D01*
X384471Y-222257D01*
X384611Y-221555D01*
X384471Y-220853D01*
X384073Y-220257D01*
X383478Y-219860D01*
X382776Y-219720D01*
D02*
G37*
G36*
X430020Y-215175D02*
X429318Y-215315D01*
X428722Y-215713D01*
X428324Y-216308D01*
X428185Y-217010D01*
X428324Y-217713D01*
X428513Y-217995D01*
X428324Y-218277D01*
X428185Y-218979D01*
X428324Y-219681D01*
X428513Y-219963D01*
X428324Y-220245D01*
X428185Y-220948D01*
X428324Y-221650D01*
X428513Y-221932D01*
X428324Y-222214D01*
X428185Y-222916D01*
X428324Y-223618D01*
X428722Y-224214D01*
X429318Y-224612D01*
X430020Y-224751D01*
X430722Y-224612D01*
X431318Y-224214D01*
X431715Y-223618D01*
X431855Y-222916D01*
X431715Y-222214D01*
X431527Y-221932D01*
X431715Y-221650D01*
X431855Y-220948D01*
X431715Y-220245D01*
X431527Y-219963D01*
X431715Y-219681D01*
X431855Y-218979D01*
X431715Y-218277D01*
X431527Y-217995D01*
X431715Y-217713D01*
X431855Y-217010D01*
X431715Y-216308D01*
X431318Y-215713D01*
X430722Y-215315D01*
X430020Y-215175D01*
D02*
G37*
G36*
X472047Y-215488D02*
X471345Y-215627D01*
X470750Y-216025D01*
X470352Y-216620D01*
X470212Y-217323D01*
X470352Y-218025D01*
X470540Y-218307D01*
X470352Y-218589D01*
X470212Y-219291D01*
X470352Y-219994D01*
X470540Y-220276D01*
X470352Y-220557D01*
X470212Y-221260D01*
X470352Y-221962D01*
X470540Y-222244D01*
X470352Y-222526D01*
X470212Y-223228D01*
X470352Y-223931D01*
X470750Y-224526D01*
X471345Y-224924D01*
X472047Y-225064D01*
X472750Y-224924D01*
X473345Y-224526D01*
X473743Y-223931D01*
X473882Y-223228D01*
X473743Y-222526D01*
X473554Y-222244D01*
X473743Y-221962D01*
X473882Y-221260D01*
X473743Y-220557D01*
X473554Y-220276D01*
X473743Y-219994D01*
X473882Y-219291D01*
X473743Y-218589D01*
X473554Y-218307D01*
X473743Y-218025D01*
X473882Y-217323D01*
X473743Y-216620D01*
X473345Y-216025D01*
X472750Y-215627D01*
X472047Y-215488D01*
D02*
G37*
G36*
X404493Y-222314D02*
X403790Y-222453D01*
X403195Y-222851D01*
X402797Y-223447D01*
X402658Y-224149D01*
X402797Y-224851D01*
X403195Y-225447D01*
X403790Y-225845D01*
X404493Y-225984D01*
X405195Y-225845D01*
X405790Y-225447D01*
X406188Y-224851D01*
X406328Y-224149D01*
X406188Y-223447D01*
X405790Y-222851D01*
X405195Y-222453D01*
X404493Y-222314D01*
D02*
G37*
G36*
X584646Y-223362D02*
X583943Y-223501D01*
X583348Y-223899D01*
X582950Y-224495D01*
X582810Y-225197D01*
X582950Y-225899D01*
X583348Y-226495D01*
X583943Y-226892D01*
X584646Y-227032D01*
X585348Y-226892D01*
X585943Y-226495D01*
X586341Y-225899D01*
X586481Y-225197D01*
X586341Y-224495D01*
X585943Y-223899D01*
X585348Y-223501D01*
X584646Y-223362D01*
D02*
G37*
G36*
X542913Y-226905D02*
X542211Y-227045D01*
X541616Y-227442D01*
X541442Y-227702D01*
X540841D01*
X540668Y-227442D01*
X540072Y-227045D01*
X539370Y-226905D01*
X538668Y-227045D01*
X538072Y-227442D01*
X537675Y-228038D01*
X537535Y-228740D01*
X537675Y-229443D01*
X538072Y-230038D01*
X538668Y-230436D01*
X539370Y-230575D01*
X540072Y-230436D01*
X540668Y-230038D01*
X540841Y-229779D01*
X541442D01*
X541616Y-230038D01*
X542211Y-230436D01*
X542913Y-230575D01*
X543616Y-230436D01*
X544211Y-230038D01*
X544609Y-229443D01*
X544749Y-228740D01*
X544609Y-228038D01*
X544211Y-227442D01*
X543616Y-227045D01*
X542913Y-226905D01*
D02*
G37*
G36*
X616929Y-224149D02*
X616227Y-224289D01*
X615631Y-224687D01*
X615234Y-225282D01*
X615094Y-225984D01*
X615234Y-226687D01*
X615631Y-227282D01*
X616227Y-227680D01*
X616929Y-227819D01*
X617631Y-227680D01*
X618227Y-227282D01*
X618625Y-226687D01*
X618764Y-225984D01*
X618625Y-225282D01*
X618227Y-224687D01*
X617631Y-224289D01*
X616929Y-224149D01*
D02*
G37*
G36*
X280315Y-224543D02*
X279613Y-224682D01*
X279017Y-225080D01*
X278619Y-225676D01*
X278480Y-226378D01*
X278619Y-227080D01*
X279017Y-227676D01*
X279489Y-227991D01*
X279613Y-228074D01*
X279497Y-228552D01*
X279353Y-228523D01*
X279134Y-228480D01*
X278432Y-228619D01*
X277836Y-229017D01*
X277438Y-229613D01*
X277299Y-230315D01*
X277438Y-231017D01*
X277836Y-231613D01*
X278432Y-232011D01*
X279134Y-232150D01*
X279836Y-232011D01*
X280432Y-231613D01*
X280829Y-231017D01*
X280969Y-230315D01*
X280829Y-229613D01*
X280432Y-229017D01*
X279960Y-228702D01*
X279836Y-228619D01*
X279952Y-228141D01*
X280095Y-228169D01*
X280315Y-228213D01*
X281017Y-228074D01*
X281613Y-227676D01*
X282011Y-227080D01*
X282150Y-226378D01*
X282011Y-225676D01*
X281613Y-225080D01*
X281017Y-224682D01*
X280315Y-224543D01*
D02*
G37*
G36*
X626987Y-226511D02*
X626285Y-226651D01*
X625690Y-227049D01*
X625292Y-227644D01*
X625152Y-228346D01*
X625292Y-229049D01*
X625690Y-229644D01*
X626285Y-230042D01*
X626987Y-230182D01*
X627690Y-230042D01*
X628285Y-229644D01*
X628683Y-229049D01*
X628823Y-228346D01*
X628683Y-227644D01*
X628285Y-227049D01*
X627690Y-226651D01*
X626987Y-226511D01*
D02*
G37*
G36*
X329134Y-226905D02*
X328432Y-227045D01*
X327836Y-227442D01*
X327438Y-228038D01*
X327299Y-228740D01*
X327438Y-229443D01*
X327836Y-230038D01*
X328432Y-230436D01*
X329134Y-230575D01*
X329836Y-230436D01*
X330432Y-230038D01*
X330829Y-229443D01*
X330969Y-228740D01*
X330829Y-228038D01*
X330432Y-227442D01*
X329836Y-227045D01*
X329134Y-226905D01*
D02*
G37*
G36*
X429528Y-229661D02*
X428825Y-229801D01*
X428230Y-230198D01*
X427832Y-230794D01*
X427692Y-231496D01*
X427832Y-232198D01*
X428230Y-232794D01*
X428825Y-233192D01*
X429528Y-233331D01*
X430230Y-233192D01*
X430825Y-232794D01*
X431223Y-232198D01*
X431363Y-231496D01*
X431223Y-230794D01*
X430825Y-230198D01*
X430230Y-229801D01*
X429528Y-229661D01*
D02*
G37*
G36*
X321654Y-230842D02*
X320951Y-230982D01*
X320356Y-231379D01*
X319958Y-231975D01*
X319818Y-232677D01*
X319958Y-233380D01*
X320356Y-233975D01*
X320951Y-234373D01*
X321654Y-234512D01*
X322356Y-234373D01*
X322951Y-233975D01*
X323349Y-233380D01*
X323489Y-232677D01*
X323349Y-231975D01*
X322951Y-231379D01*
X322356Y-230982D01*
X321654Y-230842D01*
D02*
G37*
G36*
X373093Y-231137D02*
X372391Y-231277D01*
X371796Y-231675D01*
X371398Y-232270D01*
X371258Y-232972D01*
X371398Y-233675D01*
X371796Y-234270D01*
X372391Y-234668D01*
X373093Y-234808D01*
X373796Y-234668D01*
X374391Y-234270D01*
X374789Y-233675D01*
X374929Y-232972D01*
X374789Y-232270D01*
X374391Y-231675D01*
X373796Y-231277D01*
X373093Y-231137D01*
D02*
G37*
G36*
X10007Y-233133D02*
X9305Y-233272D01*
X8710Y-233670D01*
X8312Y-234265D01*
X8172Y-234968D01*
X8312Y-235670D01*
X8710Y-236265D01*
X9305Y-236663D01*
X10007Y-236803D01*
X10710Y-236663D01*
X11305Y-236265D01*
X11703Y-235670D01*
X11843Y-234968D01*
X11703Y-234265D01*
X11305Y-233670D01*
X10710Y-233272D01*
X10007Y-233133D01*
D02*
G37*
G36*
X288D02*
X-414Y-233272D01*
X-1010Y-233670D01*
X-1407Y-234265D01*
X-1547Y-234968D01*
X-1407Y-235670D01*
X-1010Y-236265D01*
X-414Y-236663D01*
X288Y-236803D01*
X990Y-236663D01*
X1586Y-236265D01*
X1984Y-235670D01*
X2123Y-234968D01*
X1984Y-234265D01*
X1586Y-233670D01*
X990Y-233272D01*
X288Y-233133D01*
D02*
G37*
G36*
X230251Y-230431D02*
X229548Y-230571D01*
X228953Y-230969D01*
X228555Y-231564D01*
X228415Y-232266D01*
X228555Y-232969D01*
X228953Y-233564D01*
X228735Y-234020D01*
X228469Y-234417D01*
X228329Y-235119D01*
X228469Y-235822D01*
X228867Y-236417D01*
X229462Y-236815D01*
X230165Y-236954D01*
X230867Y-236815D01*
X231463Y-236417D01*
X231860Y-235822D01*
X232000Y-235119D01*
X231860Y-234417D01*
X231463Y-233822D01*
X231681Y-233366D01*
X231946Y-232969D01*
X232086Y-232266D01*
X231946Y-231564D01*
X231548Y-230969D01*
X230953Y-230571D01*
X230251Y-230431D01*
D02*
G37*
G36*
X340786Y-233992D02*
X340083Y-234131D01*
X339488Y-234529D01*
X339090Y-235124D01*
X338950Y-235827D01*
X339090Y-236529D01*
X339488Y-237124D01*
X340083Y-237522D01*
X340786Y-237662D01*
X341488Y-237522D01*
X342083Y-237124D01*
X342481Y-236529D01*
X342621Y-235827D01*
X342481Y-235124D01*
X342083Y-234529D01*
X341488Y-234131D01*
X340786Y-233992D01*
D02*
G37*
G36*
X581890Y-234090D02*
X581187Y-234230D01*
X580592Y-234628D01*
X580194Y-235223D01*
X580055Y-235925D01*
X580194Y-236628D01*
X580592Y-237223D01*
X581187Y-237621D01*
X581890Y-237760D01*
X582592Y-237621D01*
X583187Y-237223D01*
X583585Y-236628D01*
X583725Y-235925D01*
X583585Y-235223D01*
X583187Y-234628D01*
X582592Y-234230D01*
X581890Y-234090D01*
D02*
G37*
G36*
X312322Y-234385D02*
X311620Y-234525D01*
X311024Y-234923D01*
X310627Y-235518D01*
X310487Y-236221D01*
X310627Y-236923D01*
X311024Y-237518D01*
X311620Y-237916D01*
X312322Y-238056D01*
X313024Y-237916D01*
X313620Y-237518D01*
X314018Y-236923D01*
X314158Y-236221D01*
X314018Y-235518D01*
X313620Y-234923D01*
X313024Y-234525D01*
X312322Y-234385D01*
D02*
G37*
G36*
X277165D02*
X276463Y-234525D01*
X275868Y-234923D01*
X275470Y-235518D01*
X275330Y-236221D01*
X275470Y-236923D01*
X275868Y-237518D01*
X276463Y-237916D01*
X277165Y-238056D01*
X277868Y-237916D01*
X278463Y-237518D01*
X278861Y-236923D01*
X279001Y-236221D01*
X278861Y-235518D01*
X278463Y-234923D01*
X277868Y-234525D01*
X277165Y-234385D01*
D02*
G37*
G36*
X293307Y-235173D02*
X292605Y-235312D01*
X292009Y-235710D01*
X291612Y-236305D01*
X291472Y-237008D01*
X291612Y-237710D01*
X292009Y-238306D01*
X292605Y-238703D01*
X293307Y-238843D01*
X294009Y-238703D01*
X294605Y-238306D01*
X295003Y-237710D01*
X295142Y-237008D01*
X295003Y-236305D01*
X294605Y-235710D01*
X294009Y-235312D01*
X293307Y-235173D01*
D02*
G37*
G36*
X288583Y-235566D02*
X287880Y-235706D01*
X287285Y-236104D01*
X286887Y-236699D01*
X286747Y-237402D01*
X286887Y-238104D01*
X287285Y-238699D01*
X287880Y-239097D01*
X288583Y-239237D01*
X289285Y-239097D01*
X289880Y-238699D01*
X290278Y-238104D01*
X290418Y-237402D01*
X290278Y-236699D01*
X289880Y-236104D01*
X289285Y-235706D01*
X288583Y-235566D01*
D02*
G37*
G36*
X281496D02*
X280794Y-235706D01*
X280198Y-236104D01*
X279801Y-236699D01*
X279661Y-237402D01*
X279801Y-238104D01*
X280198Y-238699D01*
X280794Y-239097D01*
X281496Y-239237D01*
X282198Y-239097D01*
X282794Y-238699D01*
X283192Y-238104D01*
X283331Y-237402D01*
X283192Y-236699D01*
X282794Y-236104D01*
X282198Y-235706D01*
X281496Y-235566D01*
D02*
G37*
G36*
X36614Y-230842D02*
X35912Y-230982D01*
X35316Y-231379D01*
X34919Y-231975D01*
X34779Y-232677D01*
X34919Y-233380D01*
X35087Y-233632D01*
X34923Y-233742D01*
X34525Y-234337D01*
X34385Y-235039D01*
X34511Y-235671D01*
X34337Y-235706D01*
X33742Y-236104D01*
X33344Y-236699D01*
X33204Y-237402D01*
X33344Y-238104D01*
X33742Y-238699D01*
X34337Y-239097D01*
X35039Y-239237D01*
X35742Y-239097D01*
X36337Y-238699D01*
X36735Y-238104D01*
X36875Y-237402D01*
X36749Y-236770D01*
X36923Y-236735D01*
X37518Y-236337D01*
X37916Y-235742D01*
X38056Y-235039D01*
X37916Y-234337D01*
X37747Y-234085D01*
X37912Y-233975D01*
X38310Y-233380D01*
X38449Y-232677D01*
X38310Y-231975D01*
X37912Y-231379D01*
X37317Y-230982D01*
X36614Y-230842D01*
D02*
G37*
G36*
X14665Y-235566D02*
X13963Y-235706D01*
X13368Y-236104D01*
X12970Y-236699D01*
X12830Y-237402D01*
X12970Y-238104D01*
X13368Y-238699D01*
X13963Y-239097D01*
X14665Y-239237D01*
X15368Y-239097D01*
X15963Y-238699D01*
X16361Y-238104D01*
X16501Y-237402D01*
X16361Y-236699D01*
X15963Y-236104D01*
X15368Y-235706D01*
X14665Y-235566D01*
D02*
G37*
G36*
X408760Y-236354D02*
X408057Y-236493D01*
X407462Y-236891D01*
X407064Y-237487D01*
X406925Y-238189D01*
X407064Y-238891D01*
X407462Y-239487D01*
X408057Y-239884D01*
X408760Y-240024D01*
X409462Y-239884D01*
X410058Y-239487D01*
X410455Y-238891D01*
X410595Y-238189D01*
X410455Y-237487D01*
X410058Y-236891D01*
X409462Y-236493D01*
X408760Y-236354D01*
D02*
G37*
G36*
X19685Y-237535D02*
X18983Y-237674D01*
X18387Y-238072D01*
X17989Y-238668D01*
X17850Y-239370D01*
X17989Y-240072D01*
X18387Y-240668D01*
X18983Y-241066D01*
X19685Y-241205D01*
X20387Y-241066D01*
X20983Y-240668D01*
X21381Y-240072D01*
X21520Y-239370D01*
X21381Y-238668D01*
X20983Y-238072D01*
X20387Y-237674D01*
X19685Y-237535D01*
D02*
G37*
G36*
X333714Y-237929D02*
X333012Y-238068D01*
X332416Y-238466D01*
X332018Y-239061D01*
X331879Y-239764D01*
X332018Y-240466D01*
X332416Y-241061D01*
X333012Y-241459D01*
X333714Y-241599D01*
X334416Y-241459D01*
X335012Y-241061D01*
X335409Y-240466D01*
X335549Y-239764D01*
X335409Y-239061D01*
X335012Y-238466D01*
X334416Y-238068D01*
X333714Y-237929D01*
D02*
G37*
G36*
X231102D02*
X230400Y-238068D01*
X229805Y-238466D01*
X229407Y-239061D01*
X229267Y-239764D01*
X229407Y-240466D01*
X229805Y-241061D01*
X230400Y-241459D01*
X231102Y-241599D01*
X231805Y-241459D01*
X232400Y-241061D01*
X232798Y-240466D01*
X232938Y-239764D01*
X232798Y-239061D01*
X232400Y-238466D01*
X231805Y-238068D01*
X231102Y-237929D01*
D02*
G37*
G36*
X204331Y-230842D02*
X203628Y-230982D01*
X203033Y-231379D01*
X202635Y-231975D01*
X202496Y-232677D01*
X202635Y-233380D01*
X202911Y-233792D01*
X203033Y-233975D01*
X202801Y-234421D01*
X202639Y-234529D01*
X202241Y-235124D01*
X202102Y-235827D01*
X202241Y-236529D01*
X202561Y-237008D01*
X202241Y-237487D01*
X202102Y-238189D01*
X202241Y-238891D01*
X202500Y-239278D01*
X202110Y-239862D01*
X201970Y-240564D01*
X202110Y-241267D01*
X202507Y-241862D01*
X203103Y-242260D01*
X203805Y-242400D01*
X204507Y-242260D01*
X205103Y-241862D01*
X205501Y-241267D01*
X205640Y-240564D01*
X205501Y-239862D01*
X205242Y-239475D01*
X205633Y-238891D01*
X205772Y-238189D01*
X205633Y-237487D01*
X205313Y-237008D01*
X205633Y-236529D01*
X205772Y-235827D01*
X205633Y-235124D01*
X205357Y-234712D01*
X205235Y-234529D01*
X205467Y-234083D01*
X205628Y-233975D01*
X206026Y-233380D01*
X206166Y-232677D01*
X206026Y-231975D01*
X205628Y-231379D01*
X205033Y-230982D01*
X204331Y-230842D01*
D02*
G37*
G36*
X-23622Y-227495D02*
X-24324Y-227635D01*
X-24920Y-228033D01*
X-25318Y-228628D01*
X-25457Y-229331D01*
X-25318Y-230033D01*
X-24920Y-230628D01*
X-24324Y-231026D01*
X-24234Y-231044D01*
Y-231554D01*
X-24324Y-231572D01*
X-24920Y-231970D01*
X-25318Y-232565D01*
X-25457Y-233268D01*
X-25318Y-233970D01*
X-24920Y-234565D01*
X-24324Y-234963D01*
X-24234Y-234981D01*
Y-235491D01*
X-24324Y-235509D01*
X-24920Y-235907D01*
X-25318Y-236502D01*
X-25457Y-237205D01*
X-25318Y-237907D01*
X-24920Y-238502D01*
X-24324Y-238900D01*
X-24234Y-238918D01*
Y-239428D01*
X-24324Y-239446D01*
X-24920Y-239844D01*
X-25318Y-240439D01*
X-25457Y-241142D01*
X-25318Y-241844D01*
X-24920Y-242439D01*
X-24324Y-242837D01*
X-23622Y-242977D01*
X-22920Y-242837D01*
X-22324Y-242439D01*
X-21926Y-241844D01*
X-21787Y-241142D01*
X-21926Y-240439D01*
X-22324Y-239844D01*
X-22920Y-239446D01*
X-23010Y-239428D01*
Y-238918D01*
X-22920Y-238900D01*
X-22324Y-238502D01*
X-21926Y-237907D01*
X-21787Y-237205D01*
X-21926Y-236502D01*
X-22324Y-235907D01*
X-22920Y-235509D01*
X-23010Y-235491D01*
Y-234981D01*
X-22920Y-234963D01*
X-22324Y-234565D01*
X-21926Y-233970D01*
X-21787Y-233268D01*
X-21926Y-232565D01*
X-22324Y-231970D01*
X-22920Y-231572D01*
X-23010Y-231554D01*
Y-231044D01*
X-22920Y-231026D01*
X-22324Y-230628D01*
X-21926Y-230033D01*
X-21787Y-229331D01*
X-21926Y-228628D01*
X-22324Y-228033D01*
X-22920Y-227635D01*
X-23622Y-227495D01*
D02*
G37*
G36*
X483831Y-239503D02*
X483129Y-239643D01*
X482534Y-240041D01*
X482136Y-240636D01*
X481996Y-241339D01*
X482136Y-242041D01*
X482534Y-242636D01*
X483129Y-243034D01*
X483831Y-243174D01*
X484534Y-243034D01*
X485129Y-242636D01*
X485527Y-242041D01*
X485666Y-241339D01*
X485527Y-240636D01*
X485129Y-240041D01*
X484534Y-239643D01*
X483831Y-239503D01*
D02*
G37*
G36*
X596063Y-238060D02*
X595361Y-238199D01*
X594765Y-238597D01*
X594367Y-239193D01*
X594228Y-239895D01*
X594367Y-240597D01*
X594600Y-240945D01*
X594367Y-241293D01*
X594228Y-241995D01*
X594367Y-242697D01*
X594765Y-243293D01*
X595361Y-243690D01*
X596063Y-243830D01*
X596765Y-243690D01*
X597361Y-243293D01*
X597759Y-242697D01*
X597898Y-241995D01*
X597759Y-241293D01*
X597526Y-240945D01*
X597759Y-240597D01*
X597898Y-239895D01*
X597759Y-239193D01*
X597361Y-238597D01*
X596765Y-238199D01*
X596063Y-238060D01*
D02*
G37*
G36*
X341274Y-241078D02*
X340572Y-241218D01*
X339977Y-241616D01*
X339579Y-242211D01*
X339439Y-242913D01*
X339579Y-243616D01*
X339977Y-244211D01*
X340572Y-244609D01*
X341274Y-244749D01*
X341977Y-244609D01*
X342572Y-244211D01*
X342970Y-243616D01*
X343110Y-242913D01*
X342970Y-242211D01*
X342572Y-241616D01*
X341977Y-241218D01*
X341274Y-241078D01*
D02*
G37*
G36*
X309782Y-241472D02*
X309080Y-241612D01*
X308485Y-242009D01*
X308087Y-242605D01*
X307947Y-243307D01*
X308087Y-244009D01*
X308485Y-244605D01*
X309080Y-245003D01*
X309782Y-245142D01*
X310485Y-245003D01*
X311080Y-244605D01*
X311478Y-244009D01*
X311618Y-243307D01*
X311478Y-242605D01*
X311080Y-242009D01*
X310485Y-241612D01*
X309782Y-241472D01*
D02*
G37*
G36*
X550391Y-241475D02*
X549688Y-241615D01*
X549093Y-242012D01*
X548695Y-242608D01*
X548556Y-243310D01*
X548695Y-244012D01*
X549093Y-244608D01*
X549688Y-245006D01*
X550391Y-245145D01*
X551093Y-245006D01*
X551688Y-244608D01*
X552086Y-244012D01*
X552226Y-243310D01*
X552086Y-242608D01*
X551688Y-242012D01*
X551093Y-241615D01*
X550391Y-241475D01*
D02*
G37*
G36*
X524016Y-241964D02*
X523313Y-242104D01*
X522718Y-242501D01*
X522320Y-243097D01*
X522181Y-243799D01*
X522320Y-244501D01*
X522718Y-245097D01*
X523313Y-245495D01*
X524016Y-245635D01*
X524718Y-245495D01*
X525314Y-245097D01*
X525711Y-244501D01*
X525851Y-243799D01*
X525711Y-243097D01*
X525314Y-242501D01*
X524718Y-242104D01*
X524016Y-241964D01*
D02*
G37*
G36*
X496063Y-242259D02*
X495361Y-242399D01*
X494765Y-242797D01*
X494367Y-243392D01*
X494228Y-244094D01*
X494367Y-244797D01*
X494765Y-245392D01*
X495361Y-245790D01*
X496063Y-245930D01*
X496765Y-245790D01*
X497361Y-245392D01*
X497759Y-244797D01*
X497898Y-244094D01*
X497759Y-243392D01*
X497361Y-242797D01*
X496765Y-242399D01*
X496063Y-242259D01*
D02*
G37*
G36*
X418898Y-243440D02*
X418195Y-243580D01*
X417600Y-243978D01*
X417202Y-244573D01*
X417062Y-245276D01*
X417202Y-245978D01*
X417600Y-246573D01*
X418195Y-246971D01*
X418898Y-247111D01*
X419600Y-246971D01*
X420195Y-246573D01*
X420593Y-245978D01*
X420733Y-245276D01*
X420593Y-244573D01*
X420195Y-243978D01*
X419600Y-243580D01*
X418898Y-243440D01*
D02*
G37*
G36*
X319685D02*
X318983Y-243580D01*
X318387Y-243978D01*
X317989Y-244573D01*
X317850Y-245276D01*
X317989Y-245978D01*
X318387Y-246573D01*
X318983Y-246971D01*
X319685Y-247111D01*
X320387Y-246971D01*
X320983Y-246573D01*
X321381Y-245978D01*
X321520Y-245276D01*
X321381Y-244573D01*
X320983Y-243978D01*
X320387Y-243580D01*
X319685Y-243440D01*
D02*
G37*
G36*
X536614Y-243539D02*
X535912Y-243678D01*
X535316Y-244076D01*
X534919Y-244672D01*
X534779Y-245374D01*
X534919Y-246076D01*
X535316Y-246672D01*
X535912Y-247070D01*
X536614Y-247209D01*
X537317Y-247070D01*
X537912Y-246672D01*
X538310Y-246076D01*
X538449Y-245374D01*
X538310Y-244672D01*
X537912Y-244076D01*
X537317Y-243678D01*
X536614Y-243539D01*
D02*
G37*
G36*
X470472Y-244621D02*
X469770Y-244761D01*
X469175Y-245159D01*
X468777Y-245754D01*
X468637Y-246457D01*
X468777Y-247159D01*
X469175Y-247754D01*
X469770Y-248152D01*
X470472Y-248292D01*
X471175Y-248152D01*
X471770Y-247754D01*
X472168Y-247159D01*
X472308Y-246457D01*
X472168Y-245754D01*
X471770Y-245159D01*
X471175Y-244761D01*
X470472Y-244621D01*
D02*
G37*
G36*
X274719Y-243093D02*
X274016Y-243233D01*
X273421Y-243631D01*
X273023Y-244226D01*
X272884Y-244928D01*
X273023Y-245631D01*
X273421Y-246226D01*
X274016Y-246624D01*
X274719Y-246763D01*
X274955Y-246716D01*
X275060Y-247242D01*
X275457Y-247837D01*
X276053Y-248235D01*
X276755Y-248375D01*
X277457Y-248235D01*
X278053Y-247837D01*
X278451Y-247242D01*
X278590Y-246539D01*
X278451Y-245837D01*
X278053Y-245242D01*
X277457Y-244844D01*
X276755Y-244704D01*
X276519Y-244751D01*
X276414Y-244226D01*
X276016Y-243631D01*
X275421Y-243233D01*
X274719Y-243093D01*
D02*
G37*
G36*
X429134Y-245015D02*
X428432Y-245155D01*
X427836Y-245553D01*
X427438Y-246148D01*
X427299Y-246850D01*
X427438Y-247553D01*
X427836Y-248148D01*
X428432Y-248546D01*
X429134Y-248686D01*
X429836Y-248546D01*
X430432Y-248148D01*
X430829Y-247553D01*
X430969Y-246850D01*
X430829Y-246148D01*
X430432Y-245553D01*
X429836Y-245155D01*
X429134Y-245015D01*
D02*
G37*
G36*
X477165Y-245409D02*
X476463Y-245549D01*
X475868Y-245946D01*
X475470Y-246542D01*
X475330Y-247244D01*
X475470Y-247946D01*
X475868Y-248542D01*
X476463Y-248940D01*
X477165Y-249079D01*
X477868Y-248940D01*
X478463Y-248542D01*
X478861Y-247946D01*
X479001Y-247244D01*
X478861Y-246542D01*
X478463Y-245946D01*
X477868Y-245549D01*
X477165Y-245409D01*
D02*
G37*
G36*
X334842D02*
X334140Y-245549D01*
X333545Y-245946D01*
X333147Y-246542D01*
X333007Y-247244D01*
X333147Y-247946D01*
X333545Y-248542D01*
X334140Y-248940D01*
X334842Y-249079D01*
X335545Y-248940D01*
X336140Y-248542D01*
X336538Y-247946D01*
X336678Y-247244D01*
X336538Y-246542D01*
X336140Y-245946D01*
X335545Y-245549D01*
X334842Y-245409D01*
D02*
G37*
G36*
X464472Y-243705D02*
X463769Y-243844D01*
X463174Y-244242D01*
X462776Y-244838D01*
X462637Y-245540D01*
X462765Y-246185D01*
X462751Y-246188D01*
X462155Y-246586D01*
X461758Y-247181D01*
X461618Y-247883D01*
X461758Y-248586D01*
X462155Y-249181D01*
X462751Y-249579D01*
X463453Y-249719D01*
X464155Y-249579D01*
X464751Y-249181D01*
X465149Y-248586D01*
X465288Y-247883D01*
X465160Y-247238D01*
X465174Y-247236D01*
X465770Y-246838D01*
X466167Y-246242D01*
X466307Y-245540D01*
X466167Y-244838D01*
X465770Y-244242D01*
X465174Y-243844D01*
X464472Y-243705D01*
D02*
G37*
G36*
X396850Y-247181D02*
X396148Y-247320D01*
X395553Y-247718D01*
X395155Y-248313D01*
X395015Y-249016D01*
X395155Y-249718D01*
X395553Y-250313D01*
X396148Y-250711D01*
X396850Y-250851D01*
X397553Y-250711D01*
X398148Y-250313D01*
X398546Y-249718D01*
X398686Y-249016D01*
X398546Y-248313D01*
X398148Y-247718D01*
X397553Y-247320D01*
X396850Y-247181D01*
D02*
G37*
G36*
X390896Y-247230D02*
X390193Y-247369D01*
X389598Y-247767D01*
X389200Y-248363D01*
X389060Y-249065D01*
X389200Y-249767D01*
X389598Y-250363D01*
X390193Y-250761D01*
X390896Y-250900D01*
X391598Y-250761D01*
X392193Y-250363D01*
X392591Y-249767D01*
X392731Y-249065D01*
X392591Y-248363D01*
X392193Y-247767D01*
X391598Y-247369D01*
X390896Y-247230D01*
D02*
G37*
G36*
X386615Y-247278D02*
X385913Y-247418D01*
X385317Y-247815D01*
X384920Y-248411D01*
X384780Y-249113D01*
X384920Y-249816D01*
X385317Y-250411D01*
X385913Y-250809D01*
X386615Y-250949D01*
X387317Y-250809D01*
X387913Y-250411D01*
X388311Y-249816D01*
X388450Y-249113D01*
X388311Y-248411D01*
X387913Y-247815D01*
X387317Y-247418D01*
X386615Y-247278D01*
D02*
G37*
G36*
X401575Y-247377D02*
X400873Y-247517D01*
X400277Y-247915D01*
X399879Y-248510D01*
X399740Y-249213D01*
X399879Y-249915D01*
X400277Y-250510D01*
X400873Y-250908D01*
X401575Y-251048D01*
X402277Y-250908D01*
X402873Y-250510D01*
X403270Y-249915D01*
X403410Y-249213D01*
X403270Y-248510D01*
X402873Y-247915D01*
X402277Y-247517D01*
X401575Y-247377D01*
D02*
G37*
G36*
X522047Y-247869D02*
X521345Y-248009D01*
X520750Y-248407D01*
X520352Y-249002D01*
X520212Y-249705D01*
X520352Y-250407D01*
X520750Y-251002D01*
X521345Y-251400D01*
X522047Y-251540D01*
X522750Y-251400D01*
X523345Y-251002D01*
X523743Y-250407D01*
X523882Y-249705D01*
X523743Y-249002D01*
X523345Y-248407D01*
X522750Y-248009D01*
X522047Y-247869D01*
D02*
G37*
G36*
X378937Y-247968D02*
X378235Y-248108D01*
X377639Y-248505D01*
X377241Y-249101D01*
X377102Y-249803D01*
X377241Y-250505D01*
X377639Y-251101D01*
X378235Y-251499D01*
X378937Y-251638D01*
X379639Y-251499D01*
X380235Y-251101D01*
X380633Y-250505D01*
X380772Y-249803D01*
X380633Y-249101D01*
X380235Y-248505D01*
X379639Y-248108D01*
X378937Y-247968D01*
D02*
G37*
G36*
X614822Y-248323D02*
X614120Y-248463D01*
X613525Y-248860D01*
X613127Y-249456D01*
X612987Y-250158D01*
X613127Y-250860D01*
X613525Y-251456D01*
X614120Y-251854D01*
X614822Y-251993D01*
X615525Y-251854D01*
X616120Y-251456D01*
X616518Y-250860D01*
X616658Y-250158D01*
X616518Y-249456D01*
X616120Y-248860D01*
X615525Y-248463D01*
X614822Y-248323D01*
D02*
G37*
G36*
X538976Y-249051D02*
X538274Y-249190D01*
X537679Y-249588D01*
X537281Y-250184D01*
X537141Y-250886D01*
X537281Y-251588D01*
X537679Y-252184D01*
X538274Y-252581D01*
X538976Y-252721D01*
X539679Y-252581D01*
X540274Y-252184D01*
X540672Y-251588D01*
X540812Y-250886D01*
X540672Y-250184D01*
X540274Y-249588D01*
X539679Y-249190D01*
X538976Y-249051D01*
D02*
G37*
G36*
X508268Y-249838D02*
X507565Y-249978D01*
X506970Y-250376D01*
X506572Y-250971D01*
X506432Y-251673D01*
X506572Y-252376D01*
X506970Y-252971D01*
X507565Y-253369D01*
X508268Y-253508D01*
X508970Y-253369D01*
X509565Y-252971D01*
X509963Y-252376D01*
X510103Y-251673D01*
X509963Y-250971D01*
X509565Y-250376D01*
X508970Y-249978D01*
X508268Y-249838D01*
D02*
G37*
G36*
X230406Y-250026D02*
X229703Y-250166D01*
X229108Y-250564D01*
X228710Y-251159D01*
X228571Y-251861D01*
X228710Y-252564D01*
X229108Y-253159D01*
X229703Y-253557D01*
X230406Y-253697D01*
X231108Y-253557D01*
X231704Y-253159D01*
X232101Y-252564D01*
X232241Y-251861D01*
X232101Y-251159D01*
X231704Y-250564D01*
X231108Y-250166D01*
X230406Y-250026D01*
D02*
G37*
G36*
X618504Y-250527D02*
X617802Y-250667D01*
X617206Y-251064D01*
X616808Y-251660D01*
X616669Y-252362D01*
X616808Y-253064D01*
X617206Y-253660D01*
X617802Y-254058D01*
X618504Y-254198D01*
X619206Y-254058D01*
X619802Y-253660D01*
X620199Y-253064D01*
X620339Y-252362D01*
X620199Y-251660D01*
X619802Y-251064D01*
X619206Y-250667D01*
X618504Y-250527D01*
D02*
G37*
G36*
X605317Y-250921D02*
X604615Y-251060D01*
X604019Y-251458D01*
X603622Y-252054D01*
X603482Y-252756D01*
X603622Y-253458D01*
X604019Y-254054D01*
X604615Y-254451D01*
X605317Y-254591D01*
X606019Y-254451D01*
X606615Y-254054D01*
X607013Y-253458D01*
X607152Y-252756D01*
X607013Y-252054D01*
X606615Y-251458D01*
X606019Y-251060D01*
X605317Y-250921D01*
D02*
G37*
G36*
X318989Y-251189D02*
X318286Y-251329D01*
X317691Y-251727D01*
X317293Y-252322D01*
X317153Y-253024D01*
X317293Y-253727D01*
X317691Y-254322D01*
X318286Y-254720D01*
X318989Y-254860D01*
X319691Y-254720D01*
X320286Y-254322D01*
X320684Y-253727D01*
X320824Y-253024D01*
X320684Y-252322D01*
X320286Y-251727D01*
X319691Y-251329D01*
X318989Y-251189D01*
D02*
G37*
G36*
X571260Y-254956D02*
X570557Y-255096D01*
X570079Y-255416D01*
X569600Y-255096D01*
X568898Y-254956D01*
X568195Y-255096D01*
X567600Y-255494D01*
X567202Y-256089D01*
X567062Y-256791D01*
X567202Y-257494D01*
X567600Y-258089D01*
X568195Y-258487D01*
X568898Y-258627D01*
X569600Y-258487D01*
X570079Y-258167D01*
X570557Y-258487D01*
X571260Y-258627D01*
X571962Y-258487D01*
X572558Y-258089D01*
X572955Y-257494D01*
X573095Y-256791D01*
X572955Y-256089D01*
X572558Y-255494D01*
X571962Y-255096D01*
X571260Y-254956D01*
D02*
G37*
G36*
X476772Y-252200D02*
X476069Y-252340D01*
X475474Y-252738D01*
X475076Y-253333D01*
X474936Y-254035D01*
X475076Y-254738D01*
X475474Y-255333D01*
X476069Y-255731D01*
X476772Y-255871D01*
X477474Y-255731D01*
X478069Y-255333D01*
X478467Y-254738D01*
X478607Y-254035D01*
X478467Y-253333D01*
X478069Y-252738D01*
X477474Y-252340D01*
X476772Y-252200D01*
D02*
G37*
G36*
X381890Y-252495D02*
X381187Y-252635D01*
X380592Y-253033D01*
X380194Y-253628D01*
X380054Y-254331D01*
X380194Y-255033D01*
X380592Y-255628D01*
X381187Y-256026D01*
X381890Y-256166D01*
X382592Y-256026D01*
X383188Y-255628D01*
X383585Y-255033D01*
X383725Y-254331D01*
X383585Y-253628D01*
X383188Y-253033D01*
X382592Y-252635D01*
X381890Y-252495D01*
D02*
G37*
G36*
X513386Y-252594D02*
X512683Y-252734D01*
X512088Y-253131D01*
X511690Y-253727D01*
X511551Y-254429D01*
X511690Y-255131D01*
X512088Y-255727D01*
X512683Y-256125D01*
X513386Y-256264D01*
X514088Y-256125D01*
X514683Y-255727D01*
X515081Y-255131D01*
X515221Y-254429D01*
X515081Y-253727D01*
X514683Y-253131D01*
X514088Y-252734D01*
X513386Y-252594D01*
D02*
G37*
G36*
X243996Y-246819D02*
X243294Y-246959D01*
X242699Y-247357D01*
X242301Y-247952D01*
X242161Y-248655D01*
X242301Y-249357D01*
X242699Y-249952D01*
X243294Y-250350D01*
X243385Y-250368D01*
Y-250878D01*
X243294Y-250896D01*
X242699Y-251294D01*
X242301Y-251889D01*
X242161Y-252592D01*
X242301Y-253294D01*
X242699Y-253889D01*
X243294Y-254287D01*
X243725Y-254373D01*
X244130Y-254655D01*
X244269Y-255357D01*
X244667Y-255952D01*
X245263Y-256350D01*
X245965Y-256490D01*
X246667Y-256350D01*
X247263Y-255952D01*
X247660Y-255357D01*
X247800Y-254655D01*
X247660Y-253952D01*
X247263Y-253357D01*
X246667Y-252959D01*
X246418Y-252909D01*
Y-252400D01*
X246667Y-252350D01*
X247263Y-251952D01*
X247660Y-251357D01*
X247800Y-250655D01*
X247660Y-249952D01*
X247263Y-249357D01*
X246667Y-248959D01*
X246296Y-248885D01*
X245914Y-248695D01*
X245771Y-248348D01*
X245692Y-247952D01*
X245294Y-247357D01*
X244699Y-246959D01*
X243996Y-246819D01*
D02*
G37*
G36*
X432283Y-252889D02*
X431581Y-253029D01*
X430986Y-253427D01*
X430588Y-254022D01*
X430448Y-254724D01*
X430588Y-255427D01*
X430986Y-256022D01*
X431581Y-256420D01*
X432283Y-256560D01*
X432986Y-256420D01*
X433581Y-256022D01*
X433979Y-255427D01*
X434119Y-254724D01*
X433979Y-254022D01*
X433581Y-253427D01*
X432986Y-253029D01*
X432283Y-252889D01*
D02*
G37*
G36*
X203805Y-250346D02*
X203103Y-250486D01*
X202507Y-250884D01*
X202110Y-251479D01*
X201970Y-252182D01*
X202110Y-252884D01*
X202507Y-253479D01*
X202574Y-253524D01*
X202241Y-254022D01*
X202102Y-254724D01*
X202241Y-255427D01*
X202639Y-256022D01*
X203235Y-256420D01*
X203937Y-256560D01*
X204639Y-256420D01*
X205235Y-256022D01*
X205633Y-255427D01*
X205772Y-254724D01*
X205633Y-254022D01*
X205235Y-253427D01*
X205168Y-253382D01*
X205501Y-252884D01*
X205641Y-252182D01*
X205501Y-251479D01*
X205103Y-250884D01*
X204507Y-250486D01*
X203805Y-250346D01*
D02*
G37*
G36*
X462205Y-253283D02*
X461502Y-253423D01*
X460907Y-253820D01*
X460509Y-254416D01*
X460369Y-255118D01*
X460509Y-255820D01*
X460907Y-256416D01*
X461502Y-256814D01*
X462205Y-256953D01*
X462907Y-256814D01*
X463502Y-256416D01*
X463900Y-255820D01*
X464040Y-255118D01*
X463900Y-254416D01*
X463502Y-253820D01*
X462907Y-253423D01*
X462205Y-253283D01*
D02*
G37*
G36*
X518110Y-253381D02*
X517408Y-253521D01*
X516813Y-253919D01*
X516415Y-254514D01*
X516275Y-255217D01*
X516415Y-255919D01*
X516813Y-256514D01*
X517408Y-256912D01*
X518110Y-257052D01*
X518813Y-256912D01*
X519408Y-256514D01*
X519806Y-255919D01*
X519945Y-255217D01*
X519806Y-254514D01*
X519408Y-253919D01*
X518813Y-253521D01*
X518110Y-253381D01*
D02*
G37*
G36*
X550000Y-253775D02*
X549298Y-253915D01*
X548702Y-254312D01*
X548304Y-254908D01*
X548165Y-255610D01*
X548304Y-256313D01*
X548702Y-256908D01*
X549298Y-257306D01*
X550000Y-257446D01*
X550702Y-257306D01*
X551298Y-256908D01*
X551696Y-256313D01*
X551835Y-255610D01*
X551696Y-254908D01*
X551298Y-254312D01*
X550702Y-253915D01*
X550000Y-253775D01*
D02*
G37*
G36*
X540945Y-254169D02*
X540243Y-254308D01*
X539647Y-254706D01*
X539249Y-255302D01*
X539110Y-256004D01*
X539249Y-256706D01*
X539647Y-257302D01*
X540243Y-257699D01*
X540945Y-257839D01*
X541647Y-257699D01*
X542243Y-257302D01*
X542640Y-256706D01*
X542780Y-256004D01*
X542640Y-255302D01*
X542243Y-254706D01*
X541647Y-254308D01*
X540945Y-254169D01*
D02*
G37*
G36*
X487402Y-255153D02*
X486699Y-255293D01*
X486104Y-255691D01*
X485706Y-256286D01*
X485566Y-256988D01*
X485706Y-257691D01*
X486104Y-258286D01*
X486699Y-258684D01*
X487402Y-258823D01*
X488104Y-258684D01*
X488699Y-258286D01*
X489097Y-257691D01*
X489237Y-256988D01*
X489097Y-256286D01*
X488699Y-255691D01*
X488104Y-255293D01*
X487402Y-255153D01*
D02*
G37*
G36*
X500049Y-254798D02*
X499347Y-254938D01*
X498752Y-255336D01*
X498354Y-255931D01*
X498214Y-256633D01*
X498354Y-257336D01*
X498752Y-257931D01*
X499347Y-258329D01*
X500049Y-258469D01*
X500752Y-258329D01*
X500897Y-258232D01*
X501064Y-258483D01*
X501660Y-258881D01*
X502362Y-259020D01*
X503064Y-258881D01*
X503346Y-258692D01*
X503628Y-258881D01*
X504331Y-259020D01*
X505033Y-258881D01*
X505628Y-258483D01*
X506026Y-257887D01*
X506166Y-257185D01*
X506026Y-256483D01*
X505628Y-255887D01*
X505033Y-255489D01*
X504331Y-255350D01*
X503628Y-255489D01*
X503346Y-255678D01*
X503064Y-255489D01*
X502362Y-255350D01*
X501660Y-255489D01*
X501515Y-255587D01*
X501347Y-255336D01*
X500752Y-254938D01*
X500049Y-254798D01*
D02*
G37*
G36*
X473622Y-257220D02*
X472920Y-257360D01*
X472324Y-257757D01*
X471926Y-258353D01*
X471787Y-259055D01*
X471926Y-259757D01*
X472324Y-260353D01*
X472920Y-260751D01*
X473622Y-260890D01*
X474324Y-260751D01*
X474920Y-260353D01*
X475318Y-259757D01*
X475457Y-259055D01*
X475318Y-258353D01*
X474920Y-257757D01*
X474324Y-257360D01*
X473622Y-257220D01*
D02*
G37*
G36*
X337402Y-258795D02*
X336699Y-258934D01*
X336104Y-259332D01*
X335706Y-259928D01*
X335566Y-260630D01*
X335706Y-261332D01*
X336104Y-261928D01*
X336699Y-262326D01*
X337402Y-262465D01*
X338104Y-262326D01*
X338699Y-261928D01*
X339097Y-261332D01*
X339237Y-260630D01*
X339097Y-259928D01*
X338699Y-259332D01*
X338104Y-258934D01*
X337402Y-258795D01*
D02*
G37*
G36*
X596865Y-264561D02*
X596162Y-264701D01*
X595815Y-264933D01*
X595467Y-264701D01*
X594765Y-264561D01*
X594062Y-264701D01*
X593467Y-265098D01*
X593069Y-265694D01*
X592929Y-266396D01*
X593069Y-267098D01*
X593467Y-267694D01*
X594062Y-268092D01*
X594765Y-268231D01*
X595467Y-268092D01*
X595815Y-267859D01*
X596162Y-268092D01*
X596865Y-268231D01*
X597567Y-268092D01*
X598162Y-267694D01*
X598560Y-267098D01*
X598700Y-266396D01*
X598560Y-265694D01*
X598162Y-265098D01*
X597567Y-264701D01*
X596865Y-264561D01*
D02*
G37*
G36*
X244028Y-256662D02*
X243325Y-256802D01*
X242730Y-257199D01*
X242332Y-257795D01*
X242193Y-258497D01*
X242332Y-259200D01*
X242730Y-259795D01*
X243325Y-260193D01*
X243495Y-260226D01*
Y-260736D01*
X243325Y-260770D01*
X242730Y-261168D01*
X242332Y-261763D01*
X242193Y-262466D01*
X242332Y-263168D01*
X242730Y-263763D01*
X243325Y-264161D01*
X243710Y-264238D01*
X244130Y-264497D01*
X244269Y-265199D01*
X244667Y-265795D01*
X245263Y-266193D01*
X245965Y-266332D01*
X246667Y-266193D01*
X247263Y-265795D01*
X247660Y-265199D01*
X247800Y-264497D01*
X247660Y-263795D01*
X247263Y-263199D01*
X246667Y-262802D01*
X246418Y-262752D01*
Y-262242D01*
X246667Y-262193D01*
X247263Y-261795D01*
X247660Y-261199D01*
X247800Y-260497D01*
X247660Y-259795D01*
X247263Y-259199D01*
X246667Y-258802D01*
X246326Y-258734D01*
X245863Y-258497D01*
X245723Y-257795D01*
X245326Y-257199D01*
X244730Y-256802D01*
X244028Y-256662D01*
D02*
G37*
G36*
X486221Y-263913D02*
X485518Y-264053D01*
X484923Y-264450D01*
X484525Y-265046D01*
X484385Y-265748D01*
X484525Y-266450D01*
X484923Y-267046D01*
X485518Y-267444D01*
X486221Y-267583D01*
X486923Y-267444D01*
X487518Y-267046D01*
X487916Y-266450D01*
X488056Y-265748D01*
X487916Y-265046D01*
X487518Y-264450D01*
X486923Y-264053D01*
X486221Y-263913D01*
D02*
G37*
G36*
X585039Y-264306D02*
X584337Y-264446D01*
X583742Y-264844D01*
X583344Y-265439D01*
X583204Y-266142D01*
X583344Y-266844D01*
X583742Y-267439D01*
X584337Y-267837D01*
X585039Y-267977D01*
X585742Y-267837D01*
X586337Y-267439D01*
X586735Y-266844D01*
X586875Y-266142D01*
X586735Y-265439D01*
X586337Y-264844D01*
X585742Y-264446D01*
X585039Y-264306D01*
D02*
G37*
G36*
X-3528Y-258693D02*
X-13402D01*
Y-268567D01*
X-3528D01*
Y-258693D01*
D02*
G37*
G36*
X560630Y-267456D02*
X559928Y-267596D01*
X559332Y-267994D01*
X558934Y-268589D01*
X558795Y-269291D01*
X558934Y-269994D01*
X559332Y-270589D01*
X559928Y-270987D01*
X560630Y-271127D01*
X561332Y-270987D01*
X561928Y-270589D01*
X562325Y-269994D01*
X562465Y-269291D01*
X562325Y-268589D01*
X561928Y-267994D01*
X561332Y-267596D01*
X560630Y-267456D01*
D02*
G37*
G36*
X548425Y-267796D02*
X547723Y-267936D01*
X547127Y-268334D01*
X546730Y-268929D01*
X546590Y-269632D01*
X546730Y-270334D01*
X547127Y-270929D01*
X547723Y-271327D01*
X548425Y-271467D01*
X549127Y-271327D01*
X549723Y-270929D01*
X550121Y-270334D01*
X550260Y-269632D01*
X550121Y-268929D01*
X549723Y-268334D01*
X549127Y-267936D01*
X548425Y-267796D01*
D02*
G37*
G36*
X298819Y-267850D02*
X298117Y-267989D01*
X297521Y-268387D01*
X297123Y-268983D01*
X296984Y-269685D01*
X297123Y-270387D01*
X297521Y-270983D01*
X298117Y-271381D01*
X298819Y-271520D01*
X299521Y-271381D01*
X300117Y-270983D01*
X300515Y-270387D01*
X300654Y-269685D01*
X300515Y-268983D01*
X300117Y-268387D01*
X299521Y-267989D01*
X298819Y-267850D01*
D02*
G37*
G36*
X522047Y-269031D02*
X521345Y-269171D01*
X520750Y-269568D01*
X520352Y-270164D01*
X520212Y-270866D01*
X520352Y-271568D01*
X520750Y-272164D01*
X521345Y-272562D01*
X522047Y-272701D01*
X522750Y-272562D01*
X523345Y-272164D01*
X523743Y-271568D01*
X523882Y-270866D01*
X523743Y-270164D01*
X523345Y-269568D01*
X522750Y-269171D01*
X522047Y-269031D01*
D02*
G37*
G36*
X575197Y-268166D02*
X574370Y-268274D01*
X573600Y-268593D01*
X572939Y-269101D01*
X572432Y-269762D01*
X572113Y-270532D01*
X572004Y-271358D01*
X572113Y-272185D01*
X572432Y-272955D01*
X572939Y-273616D01*
X573600Y-274123D01*
X574370Y-274442D01*
X575197Y-274551D01*
X576023Y-274442D01*
X576793Y-274123D01*
X577454Y-273616D01*
X577962Y-272955D01*
X578281Y-272185D01*
X578390Y-271358D01*
X578281Y-270532D01*
X577962Y-269762D01*
X577454Y-269101D01*
X576793Y-268593D01*
X576023Y-268274D01*
X575197Y-268166D01*
D02*
G37*
G36*
X476378Y-271787D02*
X475676Y-271926D01*
X475080Y-272324D01*
X474682Y-272920D01*
X474543Y-273622D01*
X474682Y-274324D01*
X475080Y-274920D01*
X475676Y-275318D01*
X476378Y-275457D01*
X477080Y-275318D01*
X477676Y-274920D01*
X478074Y-274324D01*
X478213Y-273622D01*
X478074Y-272920D01*
X477676Y-272324D01*
X477080Y-271926D01*
X476378Y-271787D01*
D02*
G37*
G36*
X496457Y-267173D02*
X495373Y-267316D01*
X494364Y-267734D01*
X493497Y-268399D01*
X492832Y-269266D01*
X492414Y-270275D01*
X492271Y-271358D01*
X492414Y-272442D01*
X492832Y-273451D01*
X493497Y-274318D01*
X494364Y-274983D01*
X495373Y-275401D01*
X496457Y-275544D01*
X497540Y-275401D01*
X498549Y-274983D01*
X499416Y-274318D01*
X500081Y-273451D01*
X500499Y-272442D01*
X500642Y-271358D01*
X500499Y-270275D01*
X500081Y-269266D01*
X499416Y-268399D01*
X498549Y-267734D01*
X497540Y-267316D01*
X496457Y-267173D01*
D02*
G37*
G36*
X280382Y-272441D02*
X279679Y-272581D01*
X279084Y-272979D01*
X278686Y-273574D01*
X278547Y-274277D01*
X278686Y-274979D01*
X279084Y-275574D01*
X279679Y-275972D01*
X280382Y-276112D01*
X281084Y-275972D01*
X281680Y-275574D01*
X282077Y-274979D01*
X282217Y-274277D01*
X282077Y-273574D01*
X281680Y-272979D01*
X281084Y-272581D01*
X280382Y-272441D01*
D02*
G37*
G36*
X473303Y-274641D02*
X472601Y-274781D01*
X472006Y-275179D01*
X471608Y-275774D01*
X471468Y-276476D01*
X471608Y-277179D01*
X472006Y-277774D01*
X472601Y-278172D01*
X473303Y-278312D01*
X474006Y-278172D01*
X474601Y-277774D01*
X474999Y-277179D01*
X475139Y-276476D01*
X474999Y-275774D01*
X474601Y-275179D01*
X474006Y-274781D01*
X473303Y-274641D01*
D02*
G37*
G36*
X383071Y-274936D02*
X382369Y-275076D01*
X381773Y-275474D01*
X381375Y-276069D01*
X381236Y-276772D01*
X381375Y-277474D01*
X381773Y-278069D01*
X382369Y-278467D01*
X383071Y-278607D01*
X383773Y-278467D01*
X384369Y-278069D01*
X384766Y-277474D01*
X384906Y-276772D01*
X384766Y-276069D01*
X384369Y-275474D01*
X383773Y-275076D01*
X383071Y-274936D01*
D02*
G37*
G36*
X462473Y-275800D02*
X461771Y-275940D01*
X461175Y-276338D01*
X460778Y-276933D01*
X460638Y-277635D01*
X460778Y-278338D01*
X461175Y-278933D01*
X461771Y-279331D01*
X462473Y-279470D01*
X463176Y-279331D01*
X463771Y-278933D01*
X464169Y-278338D01*
X464309Y-277635D01*
X464169Y-276933D01*
X463771Y-276338D01*
X463176Y-275940D01*
X462473Y-275800D01*
D02*
G37*
G36*
X391339Y-276117D02*
X390636Y-276257D01*
X390041Y-276655D01*
X389643Y-277250D01*
X389503Y-277953D01*
X389643Y-278655D01*
X390041Y-279251D01*
X390636Y-279648D01*
X391339Y-279788D01*
X392041Y-279648D01*
X392636Y-279251D01*
X393034Y-278655D01*
X393174Y-277953D01*
X393034Y-277250D01*
X392636Y-276655D01*
X392041Y-276257D01*
X391339Y-276117D01*
D02*
G37*
G36*
X341339D02*
X340636Y-276257D01*
X340041Y-276655D01*
X339643Y-277250D01*
X339503Y-277953D01*
X339643Y-278655D01*
X340041Y-279251D01*
X340636Y-279648D01*
X341339Y-279788D01*
X342041Y-279648D01*
X342636Y-279251D01*
X343034Y-278655D01*
X343174Y-277953D01*
X343034Y-277250D01*
X342636Y-276655D01*
X342041Y-276257D01*
X341339Y-276117D01*
D02*
G37*
G36*
X240158Y-276905D02*
X239455Y-277045D01*
X238860Y-277442D01*
X238462Y-278038D01*
X238322Y-278740D01*
X238462Y-279443D01*
X238860Y-280038D01*
X239455Y-280436D01*
X240158Y-280575D01*
X240860Y-280436D01*
X241455Y-280038D01*
X241853Y-279443D01*
X241993Y-278740D01*
X241853Y-278038D01*
X241455Y-277442D01*
X240860Y-277045D01*
X240158Y-276905D01*
D02*
G37*
G36*
X485827Y-277594D02*
X485124Y-277734D01*
X484529Y-278131D01*
X484131Y-278727D01*
X483991Y-279429D01*
X484131Y-280132D01*
X484529Y-280727D01*
X485124Y-281125D01*
X485827Y-281264D01*
X486529Y-281125D01*
X487124Y-280727D01*
X487522Y-280132D01*
X487662Y-279429D01*
X487522Y-278727D01*
X487124Y-278131D01*
X486529Y-277734D01*
X485827Y-277594D01*
D02*
G37*
G36*
X364173Y-278480D02*
X363471Y-278619D01*
X362876Y-279017D01*
X362478Y-279613D01*
X362338Y-280315D01*
X362478Y-281017D01*
X362876Y-281613D01*
X363471Y-282011D01*
X364173Y-282150D01*
X364876Y-282011D01*
X365471Y-281613D01*
X365869Y-281017D01*
X366008Y-280315D01*
X365869Y-279613D01*
X365471Y-279017D01*
X364876Y-278619D01*
X364173Y-278480D01*
D02*
G37*
G36*
X574406Y-278972D02*
X573703Y-279111D01*
X573108Y-279509D01*
X572710Y-280104D01*
X572571Y-280807D01*
X572710Y-281509D01*
X573108Y-282104D01*
X573703Y-282502D01*
X574406Y-282642D01*
X575108Y-282502D01*
X575703Y-282104D01*
X576101Y-281509D01*
X576241Y-280807D01*
X576101Y-280104D01*
X575703Y-279509D01*
X575108Y-279111D01*
X574406Y-278972D01*
D02*
G37*
G36*
X402756Y-279267D02*
X402054Y-279407D01*
X401458Y-279805D01*
X401060Y-280400D01*
X400921Y-281102D01*
X401060Y-281805D01*
X401458Y-282400D01*
X402054Y-282798D01*
X402756Y-282938D01*
X403458Y-282798D01*
X404054Y-282400D01*
X404452Y-281805D01*
X404591Y-281102D01*
X404452Y-280400D01*
X404054Y-279805D01*
X403458Y-279407D01*
X402756Y-279267D01*
D02*
G37*
G36*
X-4724Y-281236D02*
X-5427Y-281375D01*
X-6022Y-281773D01*
X-6420Y-282368D01*
X-6560Y-283071D01*
X-6420Y-283773D01*
X-6022Y-284369D01*
X-5427Y-284766D01*
X-4724Y-284906D01*
X-4022Y-284766D01*
X-3427Y-284369D01*
X-3029Y-283773D01*
X-2889Y-283071D01*
X-3029Y-282368D01*
X-3427Y-281773D01*
X-4022Y-281375D01*
X-4724Y-281236D01*
D02*
G37*
G36*
X321850Y-281629D02*
X321148Y-281769D01*
X320553Y-282167D01*
X320155Y-282762D01*
X320015Y-283465D01*
X320155Y-284167D01*
X320553Y-284762D01*
X321148Y-285160D01*
X321850Y-285300D01*
X322553Y-285160D01*
X323148Y-284762D01*
X323546Y-284167D01*
X323686Y-283465D01*
X323546Y-282762D01*
X323148Y-282167D01*
X322553Y-281769D01*
X321850Y-281629D01*
D02*
G37*
G36*
X313386D02*
X312684Y-281769D01*
X312088Y-282167D01*
X311690Y-282762D01*
X311551Y-283465D01*
X311690Y-284167D01*
X312088Y-284762D01*
X312684Y-285160D01*
X313386Y-285300D01*
X314088Y-285160D01*
X314684Y-284762D01*
X315081Y-284167D01*
X315221Y-283465D01*
X315081Y-282762D01*
X314684Y-282167D01*
X314088Y-281769D01*
X313386Y-281629D01*
D02*
G37*
G36*
X336614Y-284385D02*
X335912Y-284525D01*
X335316Y-284923D01*
X334919Y-285518D01*
X334779Y-286221D01*
X334919Y-286923D01*
X335316Y-287518D01*
X335912Y-287916D01*
X336614Y-288056D01*
X337316Y-287916D01*
X337912Y-287518D01*
X338310Y-286923D01*
X338449Y-286221D01*
X338310Y-285518D01*
X337912Y-284923D01*
X337316Y-284525D01*
X336614Y-284385D01*
D02*
G37*
G36*
X280414Y-281643D02*
X279711Y-281783D01*
X279116Y-282181D01*
X278718Y-282776D01*
X278578Y-283478D01*
X278718Y-284180D01*
X279116Y-284776D01*
X279711Y-285174D01*
X279960Y-285223D01*
Y-285733D01*
X279711Y-285783D01*
X279116Y-286180D01*
X278718Y-286776D01*
X278578Y-287478D01*
X278718Y-288180D01*
X279116Y-288776D01*
X279711Y-289174D01*
X280414Y-289314D01*
X281116Y-289174D01*
X281711Y-288776D01*
X282109Y-288180D01*
X282249Y-287478D01*
X282109Y-286776D01*
X281711Y-286180D01*
X281116Y-285783D01*
X280867Y-285733D01*
Y-285223D01*
X281116Y-285174D01*
X281711Y-284776D01*
X282109Y-284180D01*
X282249Y-283478D01*
X282109Y-282776D01*
X281711Y-282181D01*
X281116Y-281783D01*
X280414Y-281643D01*
D02*
G37*
G36*
X315945Y-285960D02*
X315243Y-286100D01*
X314647Y-286498D01*
X314249Y-287093D01*
X314110Y-287795D01*
X314249Y-288498D01*
X314647Y-289093D01*
X315243Y-289491D01*
X315945Y-289631D01*
X316647Y-289491D01*
X317243Y-289093D01*
X317640Y-288498D01*
X317780Y-287795D01*
X317640Y-287093D01*
X317243Y-286498D01*
X316647Y-286100D01*
X315945Y-285960D01*
D02*
G37*
G36*
X35039Y-283992D02*
X34337Y-284131D01*
X33742Y-284529D01*
X33344Y-285124D01*
X33204Y-285827D01*
X33344Y-286529D01*
X33742Y-287124D01*
X34337Y-287522D01*
X34923Y-287639D01*
Y-288149D01*
X34676Y-288198D01*
X34337Y-288265D01*
X33742Y-288663D01*
X33344Y-289258D01*
X33204Y-289961D01*
X33344Y-290663D01*
X33742Y-291258D01*
X34337Y-291656D01*
X35039Y-291796D01*
X35742Y-291656D01*
X36337Y-291258D01*
X36735Y-290663D01*
X36875Y-289961D01*
X36735Y-289258D01*
X36337Y-288663D01*
X35742Y-288265D01*
X35156Y-288149D01*
Y-287639D01*
X35402Y-287590D01*
X35742Y-287522D01*
X36337Y-287124D01*
X36735Y-286529D01*
X36875Y-285827D01*
X36735Y-285124D01*
X36337Y-284529D01*
X35742Y-284131D01*
X35039Y-283992D01*
D02*
G37*
G36*
X483465Y-289700D02*
X482762Y-289840D01*
X482167Y-290238D01*
X481769Y-290833D01*
X481629Y-291535D01*
X481769Y-292238D01*
X482167Y-292833D01*
X482762Y-293231D01*
X483465Y-293371D01*
X484167Y-293231D01*
X484762Y-292833D01*
X485160Y-292238D01*
X485300Y-291535D01*
X485160Y-290833D01*
X484762Y-290238D01*
X484167Y-289840D01*
X483465Y-289700D01*
D02*
G37*
G36*
X284646Y-289897D02*
X283943Y-290037D01*
X283348Y-290435D01*
X282950Y-291030D01*
X282810Y-291732D01*
X282950Y-292435D01*
X283348Y-293030D01*
X283943Y-293428D01*
X284646Y-293567D01*
X285348Y-293428D01*
X285943Y-293030D01*
X286341Y-292435D01*
X286481Y-291732D01*
X286341Y-291030D01*
X285943Y-290435D01*
X285348Y-290037D01*
X284646Y-289897D01*
D02*
G37*
G36*
X432579Y-281415D02*
X431877Y-281555D01*
X431281Y-281953D01*
X430884Y-282548D01*
X430744Y-283251D01*
X430884Y-283953D01*
X431281Y-284548D01*
X431322Y-284576D01*
Y-285075D01*
X431281Y-285103D01*
X430884Y-285698D01*
X430744Y-286400D01*
X430884Y-287103D01*
X431214Y-287598D01*
X431423Y-288060D01*
X431025Y-288655D01*
X430885Y-289358D01*
X431025Y-290060D01*
X431414Y-290642D01*
X431139Y-291053D01*
X431000Y-291755D01*
X431139Y-292457D01*
X431537Y-293053D01*
X432132Y-293450D01*
X432835Y-293590D01*
X433537Y-293450D01*
X434132Y-293053D01*
X434530Y-292457D01*
X434670Y-291755D01*
X434530Y-291053D01*
X434141Y-290471D01*
X434416Y-290060D01*
X434556Y-289358D01*
X434416Y-288655D01*
X434085Y-288160D01*
X433877Y-287698D01*
X434275Y-287103D01*
X434414Y-286400D01*
X434275Y-285698D01*
X433877Y-285103D01*
X433836Y-285075D01*
Y-284576D01*
X433877Y-284548D01*
X434275Y-283953D01*
X434414Y-283251D01*
X434275Y-282548D01*
X433877Y-281953D01*
X433281Y-281555D01*
X432579Y-281415D01*
D02*
G37*
G36*
X10630Y-290291D02*
X9928Y-290430D01*
X9332Y-290828D01*
X8934Y-291424D01*
X8795Y-292126D01*
X8934Y-292828D01*
X9332Y-293424D01*
X9928Y-293822D01*
X10630Y-293961D01*
X11332Y-293822D01*
X11928Y-293424D01*
X12325Y-292828D01*
X12465Y-292126D01*
X12325Y-291424D01*
X11928Y-290828D01*
X11332Y-290430D01*
X10630Y-290291D01*
D02*
G37*
G36*
X345161Y-291078D02*
X344459Y-291218D01*
X343863Y-291616D01*
X343465Y-292211D01*
X343326Y-292913D01*
X343465Y-293616D01*
X343863Y-294211D01*
X344459Y-294609D01*
X345161Y-294749D01*
X345863Y-294609D01*
X346459Y-294211D01*
X346856Y-293616D01*
X346996Y-292913D01*
X346856Y-292211D01*
X346459Y-291616D01*
X345863Y-291218D01*
X345161Y-291078D01*
D02*
G37*
G36*
X325776Y-291865D02*
X325074Y-292005D01*
X324478Y-292403D01*
X324080Y-292999D01*
X323941Y-293701D01*
X324080Y-294403D01*
X324478Y-294999D01*
X325074Y-295396D01*
X325776Y-295536D01*
X326478Y-295396D01*
X327074Y-294999D01*
X327472Y-294403D01*
X327611Y-293701D01*
X327472Y-292999D01*
X327074Y-292403D01*
X326478Y-292005D01*
X325776Y-291865D01*
D02*
G37*
G36*
X246162Y-291898D02*
X245459Y-292038D01*
X244864Y-292436D01*
X244466Y-293031D01*
X244326Y-293733D01*
X244466Y-294436D01*
X244864Y-295031D01*
X245459Y-295429D01*
X246162Y-295569D01*
X246864Y-295429D01*
X247459Y-295031D01*
X247857Y-294436D01*
X247997Y-293733D01*
X247857Y-293031D01*
X247459Y-292436D01*
X246864Y-292038D01*
X246162Y-291898D01*
D02*
G37*
G36*
X280414Y-291947D02*
X279711Y-292087D01*
X279116Y-292484D01*
X278718Y-293080D01*
X278578Y-293782D01*
X278718Y-294484D01*
X279116Y-295080D01*
X279711Y-295478D01*
X280414Y-295617D01*
X281116Y-295478D01*
X281711Y-295080D01*
X282109Y-294484D01*
X282249Y-293782D01*
X282109Y-293080D01*
X281711Y-292484D01*
X281116Y-292087D01*
X280414Y-291947D01*
D02*
G37*
G36*
X-23622Y-280645D02*
X-24324Y-280785D01*
X-24920Y-281183D01*
X-25318Y-281778D01*
X-25457Y-282480D01*
X-25318Y-283183D01*
X-24920Y-283778D01*
X-24324Y-284176D01*
X-24234Y-284194D01*
Y-284704D01*
X-24324Y-284722D01*
X-24920Y-285120D01*
X-25318Y-285715D01*
X-25457Y-286417D01*
X-25318Y-287120D01*
X-24920Y-287715D01*
X-24324Y-288113D01*
X-24234Y-288131D01*
Y-288641D01*
X-24324Y-288659D01*
X-24920Y-289057D01*
X-25318Y-289652D01*
X-25457Y-290354D01*
X-25318Y-291057D01*
X-24920Y-291652D01*
X-24324Y-292050D01*
X-24234Y-292068D01*
Y-292578D01*
X-24324Y-292596D01*
X-24920Y-292994D01*
X-25318Y-293589D01*
X-25457Y-294291D01*
X-25318Y-294994D01*
X-24920Y-295589D01*
X-24324Y-295987D01*
X-23622Y-296127D01*
X-22920Y-295987D01*
X-22324Y-295589D01*
X-21926Y-294994D01*
X-21787Y-294291D01*
X-21926Y-293589D01*
X-22324Y-292994D01*
X-22920Y-292596D01*
X-23010Y-292578D01*
Y-292068D01*
X-22920Y-292050D01*
X-22324Y-291652D01*
X-21926Y-291057D01*
X-21787Y-290354D01*
X-21926Y-289652D01*
X-22324Y-289057D01*
X-22920Y-288659D01*
X-23010Y-288641D01*
Y-288131D01*
X-22920Y-288113D01*
X-22324Y-287715D01*
X-21926Y-287120D01*
X-21787Y-286417D01*
X-21926Y-285715D01*
X-22324Y-285120D01*
X-22920Y-284722D01*
X-23010Y-284704D01*
Y-284194D01*
X-22920Y-284176D01*
X-22324Y-283778D01*
X-21926Y-283183D01*
X-21787Y-282480D01*
X-21926Y-281778D01*
X-22324Y-281183D01*
X-22920Y-280785D01*
X-23622Y-280645D01*
D02*
G37*
G36*
X14173Y-292484D02*
X13471Y-292624D01*
X12876Y-293022D01*
X12478Y-293617D01*
X12338Y-294320D01*
X12478Y-295022D01*
X12876Y-295617D01*
X13471Y-296015D01*
X14173Y-296155D01*
X14876Y-296015D01*
X15471Y-295617D01*
X15869Y-295022D01*
X16008Y-294320D01*
X15869Y-293617D01*
X15471Y-293022D01*
X14876Y-292624D01*
X14173Y-292484D01*
D02*
G37*
G36*
X476772Y-290094D02*
X476069Y-290234D01*
X475474Y-290631D01*
X475076Y-291227D01*
X474936Y-291929D01*
X475076Y-292631D01*
X475474Y-293227D01*
X476069Y-293625D01*
X476772Y-293764D01*
X477213Y-293676D01*
X477295Y-293725D01*
X477601Y-294095D01*
X477495Y-294626D01*
X477635Y-295329D01*
X478033Y-295924D01*
X478628Y-296322D01*
X479331Y-296462D01*
X480033Y-296322D01*
X480628Y-295924D01*
X481026Y-295329D01*
X481166Y-294626D01*
X481026Y-293924D01*
X480628Y-293329D01*
X480033Y-292931D01*
X479331Y-292791D01*
X478889Y-292879D01*
X478807Y-292831D01*
X478501Y-292460D01*
X478607Y-291929D01*
X478467Y-291227D01*
X478069Y-290631D01*
X477474Y-290234D01*
X476772Y-290094D01*
D02*
G37*
G36*
X261082Y-292579D02*
X260269Y-292740D01*
X259580Y-293201D01*
X259120Y-293890D01*
X258958Y-294702D01*
X259120Y-295515D01*
X259580Y-296204D01*
X260269Y-296665D01*
X261082Y-296826D01*
X261894Y-296665D01*
X262584Y-296204D01*
X263044Y-295515D01*
X263206Y-294702D01*
X263044Y-293890D01*
X262584Y-293201D01*
X261894Y-292740D01*
X261082Y-292579D01*
D02*
G37*
G36*
X448573Y-292588D02*
X447760Y-292750D01*
X447071Y-293210D01*
X446611Y-293899D01*
X446449Y-294712D01*
X446611Y-295525D01*
X447071Y-296214D01*
X447760Y-296674D01*
X448573Y-296836D01*
X449385Y-296674D01*
X450074Y-296214D01*
X450535Y-295525D01*
X450697Y-294712D01*
X450535Y-293899D01*
X450074Y-293210D01*
X449385Y-292750D01*
X448573Y-292588D01*
D02*
G37*
G36*
X551968Y-295802D02*
X551266Y-295942D01*
X550671Y-296340D01*
X550273Y-296936D01*
X550133Y-297638D01*
X550273Y-298340D01*
X550671Y-298936D01*
X551266Y-299333D01*
X551968Y-299473D01*
X552671Y-299333D01*
X553266Y-298936D01*
X553664Y-298340D01*
X553804Y-297638D01*
X553664Y-296936D01*
X553266Y-296340D01*
X552671Y-295942D01*
X551968Y-295802D01*
D02*
G37*
G36*
X507480Y-296295D02*
X506778Y-296434D01*
X506183Y-296832D01*
X505785Y-297428D01*
X505645Y-298130D01*
X505785Y-298832D01*
X506183Y-299428D01*
X506778Y-299826D01*
X507480Y-299965D01*
X508183Y-299826D01*
X508778Y-299428D01*
X509176Y-298832D01*
X509316Y-298130D01*
X509176Y-297428D01*
X508778Y-296832D01*
X508183Y-296434D01*
X507480Y-296295D01*
D02*
G37*
G36*
X466142Y-292850D02*
X465439Y-292989D01*
X464844Y-293387D01*
X464446Y-293983D01*
X464306Y-294685D01*
X464446Y-295387D01*
X464844Y-295983D01*
X465103Y-296156D01*
Y-296757D01*
X464844Y-296931D01*
X464446Y-297526D01*
X464306Y-298228D01*
X464446Y-298931D01*
X464844Y-299526D01*
X465439Y-299924D01*
X466142Y-300064D01*
X466844Y-299924D01*
X467440Y-299526D01*
X467837Y-298931D01*
X467977Y-298228D01*
X467837Y-297526D01*
X467440Y-296931D01*
X467180Y-296757D01*
Y-296156D01*
X467440Y-295983D01*
X467837Y-295387D01*
X467977Y-294685D01*
X467837Y-293983D01*
X467440Y-293387D01*
X466844Y-292989D01*
X466142Y-292850D01*
D02*
G37*
G36*
X27067Y-296891D02*
X26365Y-297031D01*
X25769Y-297429D01*
X25371Y-298024D01*
X25232Y-298727D01*
X25371Y-299429D01*
X25769Y-300024D01*
X26365Y-300422D01*
X27067Y-300562D01*
X27769Y-300422D01*
X28365Y-300024D01*
X28763Y-299429D01*
X28902Y-298727D01*
X28763Y-298024D01*
X28365Y-297429D01*
X27769Y-297031D01*
X27067Y-296891D01*
D02*
G37*
G36*
X336811Y-297563D02*
X336109Y-297703D01*
X335513Y-298101D01*
X335116Y-298696D01*
X334976Y-299399D01*
X335116Y-300101D01*
X335513Y-300696D01*
X336109Y-301094D01*
X336811Y-301234D01*
X337513Y-301094D01*
X338109Y-300696D01*
X338507Y-300101D01*
X338646Y-299399D01*
X338507Y-298696D01*
X338109Y-298101D01*
X337513Y-297703D01*
X336811Y-297563D01*
D02*
G37*
G36*
X315333Y-297595D02*
X314631Y-297735D01*
X314036Y-298133D01*
X313638Y-298728D01*
X313498Y-299430D01*
X313638Y-300133D01*
X314036Y-300728D01*
X314631Y-301126D01*
X315333Y-301266D01*
X316036Y-301126D01*
X316631Y-300728D01*
X317029Y-300133D01*
X317169Y-299430D01*
X317029Y-298728D01*
X316631Y-298133D01*
X316036Y-297735D01*
X315333Y-297595D01*
D02*
G37*
G36*
X610236Y-298165D02*
X609534Y-298304D01*
X608939Y-298702D01*
X608541Y-299298D01*
X608401Y-300000D01*
X608541Y-300702D01*
X608939Y-301298D01*
X609534Y-301696D01*
X610236Y-301835D01*
X610939Y-301696D01*
X611534Y-301298D01*
X611932Y-300702D01*
X612072Y-300000D01*
X611932Y-299298D01*
X611534Y-298702D01*
X610939Y-298304D01*
X610236Y-298165D01*
D02*
G37*
G36*
X308268D02*
X307565Y-298304D01*
X306970Y-298702D01*
X306572Y-299298D01*
X306433Y-300000D01*
X306572Y-300702D01*
X306970Y-301298D01*
X307565Y-301696D01*
X308268Y-301835D01*
X308970Y-301696D01*
X309565Y-301298D01*
X309963Y-300702D01*
X310103Y-300000D01*
X309963Y-299298D01*
X309565Y-298702D01*
X308970Y-298304D01*
X308268Y-298165D01*
D02*
G37*
G36*
X495866Y-301708D02*
X495164Y-301848D01*
X494568Y-302246D01*
X494395Y-302505D01*
X493794D01*
X493621Y-302246D01*
X493025Y-301848D01*
X492323Y-301708D01*
X491620Y-301848D01*
X491025Y-302246D01*
X490627Y-302841D01*
X490488Y-303543D01*
X490627Y-304246D01*
X491025Y-304841D01*
X491620Y-305239D01*
X492323Y-305379D01*
X493025Y-305239D01*
X493621Y-304841D01*
X493794Y-304582D01*
X494395D01*
X494568Y-304841D01*
X495164Y-305239D01*
X495866Y-305379D01*
X496568Y-305239D01*
X497164Y-304841D01*
X497562Y-304246D01*
X497701Y-303543D01*
X497562Y-302841D01*
X497164Y-302246D01*
X496568Y-301848D01*
X495866Y-301708D01*
D02*
G37*
G36*
X548819Y-298952D02*
X548117Y-299092D01*
X547521Y-299490D01*
X547123Y-300085D01*
X546984Y-300787D01*
X547123Y-301490D01*
X547521Y-302085D01*
X548117Y-302483D01*
X548819Y-302623D01*
X549521Y-302483D01*
X550117Y-302085D01*
X550515Y-301490D01*
X550654Y-300787D01*
X550515Y-300085D01*
X550117Y-299490D01*
X549521Y-299092D01*
X548819Y-298952D01*
D02*
G37*
G36*
X530709D02*
X530006Y-299092D01*
X529411Y-299490D01*
X529013Y-300085D01*
X528873Y-300787D01*
X529013Y-301490D01*
X529411Y-302085D01*
X530006Y-302483D01*
X530709Y-302623D01*
X531411Y-302483D01*
X532006Y-302085D01*
X532404Y-301490D01*
X532544Y-300787D01*
X532404Y-300085D01*
X532006Y-299490D01*
X531411Y-299092D01*
X530709Y-298952D01*
D02*
G37*
G36*
X324184Y-300358D02*
X323482Y-300498D01*
X322887Y-300896D01*
X322489Y-301491D01*
X322349Y-302194D01*
X322489Y-302896D01*
X322887Y-303491D01*
X323482Y-303889D01*
X324184Y-304029D01*
X324887Y-303889D01*
X325482Y-303491D01*
X325880Y-302896D01*
X326020Y-302194D01*
X325880Y-301491D01*
X325482Y-300896D01*
X324887Y-300498D01*
X324184Y-300358D01*
D02*
G37*
G36*
X513406Y-301067D02*
X512704Y-301207D01*
X512108Y-301605D01*
X511710Y-302200D01*
X511571Y-302902D01*
X511710Y-303605D01*
X512108Y-304200D01*
X512704Y-304598D01*
X513406Y-304738D01*
X514108Y-304598D01*
X514704Y-304200D01*
X515101Y-303605D01*
X515241Y-302902D01*
X515101Y-302200D01*
X514704Y-301605D01*
X514108Y-301207D01*
X513406Y-301067D01*
D02*
G37*
G36*
X569685Y-301314D02*
X568983Y-301454D01*
X568387Y-301852D01*
X567989Y-302447D01*
X567850Y-303150D01*
X567989Y-303852D01*
X568387Y-304447D01*
X568983Y-304845D01*
X569685Y-304985D01*
X570387Y-304845D01*
X570983Y-304447D01*
X571381Y-303852D01*
X571520Y-303150D01*
X571381Y-302447D01*
X570983Y-301852D01*
X570387Y-301454D01*
X569685Y-301314D01*
D02*
G37*
G36*
X552756Y-303283D02*
X552054Y-303423D01*
X551458Y-303820D01*
X551060Y-304416D01*
X550921Y-305118D01*
X551060Y-305820D01*
X551458Y-306416D01*
X552054Y-306814D01*
X552756Y-306953D01*
X553458Y-306814D01*
X554054Y-306416D01*
X554452Y-305820D01*
X554591Y-305118D01*
X554452Y-304416D01*
X554054Y-303820D01*
X553458Y-303423D01*
X552756Y-303283D01*
D02*
G37*
G36*
X544882D02*
X544180Y-303423D01*
X543584Y-303820D01*
X543186Y-304416D01*
X543047Y-305118D01*
X543186Y-305820D01*
X543584Y-306416D01*
X544180Y-306814D01*
X544882Y-306953D01*
X545584Y-306814D01*
X546180Y-306416D01*
X546578Y-305820D01*
X546717Y-305118D01*
X546578Y-304416D01*
X546180Y-303820D01*
X545584Y-303423D01*
X544882Y-303283D01*
D02*
G37*
G36*
X461024Y-300921D02*
X460321Y-301060D01*
X459726Y-301458D01*
X459328Y-302054D01*
X459188Y-302756D01*
X459328Y-303458D01*
X459726Y-304054D01*
X459890Y-304164D01*
X459722Y-304416D01*
X459582Y-305118D01*
X459722Y-305820D01*
X460120Y-306416D01*
X460715Y-306814D01*
X461417Y-306953D01*
X462120Y-306814D01*
X462715Y-306416D01*
X463113Y-305820D01*
X463253Y-305118D01*
X463113Y-304416D01*
X462715Y-303820D01*
X462551Y-303711D01*
X462719Y-303458D01*
X462859Y-302756D01*
X462719Y-302054D01*
X462321Y-301458D01*
X461726Y-301060D01*
X461024Y-300921D01*
D02*
G37*
G36*
X498425Y-305251D02*
X497723Y-305391D01*
X497127Y-305789D01*
X496730Y-306384D01*
X496590Y-307087D01*
X496730Y-307789D01*
X497022Y-308227D01*
X496740Y-308681D01*
X496620Y-308657D01*
X495918Y-308797D01*
X495322Y-309194D01*
X495235Y-309325D01*
X494650Y-309300D01*
X494408Y-308939D01*
X493813Y-308541D01*
X493110Y-308401D01*
X492408Y-308541D01*
X491813Y-308939D01*
X491639Y-309198D01*
X491038D01*
X490865Y-308939D01*
X490269Y-308541D01*
X489567Y-308401D01*
X488865Y-308541D01*
X488269Y-308939D01*
X487871Y-309534D01*
X487732Y-310236D01*
X487871Y-310939D01*
X488269Y-311534D01*
X488865Y-311932D01*
X489567Y-312071D01*
X490269Y-311932D01*
X490865Y-311534D01*
X491038Y-311275D01*
X491639D01*
X491813Y-311534D01*
X492408Y-311932D01*
X493110Y-312071D01*
X493813Y-311932D01*
X494408Y-311534D01*
X494495Y-311404D01*
X495080Y-311428D01*
X495322Y-311790D01*
X495918Y-312188D01*
X496620Y-312327D01*
X497322Y-312188D01*
X497918Y-311790D01*
X498315Y-311194D01*
X498455Y-310492D01*
X498315Y-309790D01*
X498023Y-309352D01*
X498306Y-308898D01*
X498425Y-308922D01*
X499127Y-308782D01*
X499723Y-308384D01*
X500121Y-307789D01*
X500260Y-307087D01*
X500121Y-306384D01*
X499723Y-305789D01*
X499127Y-305391D01*
X498425Y-305251D01*
D02*
G37*
G36*
X454775Y-306730D02*
X454073Y-306870D01*
X453478Y-307268D01*
X453080Y-307863D01*
X452940Y-308565D01*
X453080Y-309268D01*
X453478Y-309863D01*
X454073Y-310261D01*
X454775Y-310401D01*
X455478Y-310261D01*
X456073Y-309863D01*
X456471Y-309268D01*
X456611Y-308565D01*
X456471Y-307863D01*
X456073Y-307268D01*
X455478Y-306870D01*
X454775Y-306730D01*
D02*
G37*
G36*
X461417Y-310263D02*
X460715Y-310403D01*
X460120Y-310801D01*
X459722Y-311396D01*
X459582Y-312099D01*
X459722Y-312801D01*
X460120Y-313396D01*
X460715Y-313794D01*
X461417Y-313934D01*
X462120Y-313794D01*
X462715Y-313396D01*
X463113Y-312801D01*
X463253Y-312099D01*
X463113Y-311396D01*
X462715Y-310801D01*
X462120Y-310403D01*
X461417Y-310263D01*
D02*
G37*
G36*
X622221Y-311646D02*
X621519Y-311785D01*
X620923Y-312183D01*
X620525Y-312778D01*
X620386Y-313481D01*
X620525Y-314183D01*
X620923Y-314778D01*
X621519Y-315176D01*
X622221Y-315316D01*
X622923Y-315176D01*
X623519Y-314778D01*
X623916Y-314183D01*
X624056Y-313481D01*
X623916Y-312778D01*
X623519Y-312183D01*
X622923Y-311785D01*
X622221Y-311646D01*
D02*
G37*
G36*
X473819Y-313519D02*
X473117Y-313659D01*
X472521Y-314057D01*
X472123Y-314652D01*
X471984Y-315354D01*
X472123Y-316057D01*
X472521Y-316652D01*
X473117Y-317050D01*
X473819Y-317190D01*
X474521Y-317050D01*
X475117Y-316652D01*
X475515Y-316057D01*
X475654Y-315354D01*
X475515Y-314652D01*
X475117Y-314057D01*
X474521Y-313659D01*
X473819Y-313519D01*
D02*
G37*
G36*
X484842Y-315881D02*
X484140Y-316021D01*
X483545Y-316419D01*
X483147Y-317014D01*
X483007Y-317717D01*
X483147Y-318419D01*
X483545Y-319014D01*
X484140Y-319412D01*
X484842Y-319552D01*
X485545Y-319412D01*
X486140Y-319014D01*
X486538Y-318419D01*
X486678Y-317717D01*
X486538Y-317014D01*
X486140Y-316419D01*
X485545Y-316021D01*
X484842Y-315881D01*
D02*
G37*
G36*
X-3528Y-311844D02*
X-13402D01*
Y-321718D01*
X-3528D01*
Y-311844D01*
D02*
G37*
G36*
X556841Y-317622D02*
X555867Y-317816D01*
X555041Y-318368D01*
X554490Y-319193D01*
X554296Y-320167D01*
X554490Y-321141D01*
X555041Y-321967D01*
X555867Y-322519D01*
X556841Y-322712D01*
X557815Y-322519D01*
X558640Y-321967D01*
X559192Y-321141D01*
X559386Y-320167D01*
X559192Y-319193D01*
X558640Y-318368D01*
X557815Y-317816D01*
X556841Y-317622D01*
D02*
G37*
G36*
X541093D02*
X540119Y-317816D01*
X539293Y-318368D01*
X538742Y-319193D01*
X538548Y-320167D01*
X538742Y-321141D01*
X539293Y-321967D01*
X540119Y-322519D01*
X541093Y-322712D01*
X542067Y-322519D01*
X542893Y-321967D01*
X543444Y-321141D01*
X543638Y-320167D01*
X543444Y-319193D01*
X542893Y-318368D01*
X542067Y-317816D01*
X541093Y-317622D01*
D02*
G37*
G36*
X509597D02*
X508623Y-317816D01*
X507797Y-318368D01*
X507246Y-319193D01*
X507052Y-320167D01*
X507246Y-321141D01*
X507797Y-321967D01*
X508623Y-322519D01*
X509597Y-322712D01*
X510571Y-322519D01*
X511397Y-321967D01*
X511948Y-321141D01*
X512142Y-320167D01*
X511948Y-319193D01*
X511397Y-318368D01*
X510571Y-317816D01*
X509597Y-317622D01*
D02*
G37*
G36*
X200876Y-308685D02*
X199504Y-308820D01*
X198184Y-309221D01*
X196968Y-309871D01*
X195902Y-310745D01*
X195027Y-311811D01*
X194377Y-313027D01*
X193977Y-314347D01*
X193842Y-315719D01*
X193977Y-317091D01*
X194377Y-318411D01*
X195027Y-319627D01*
X195902Y-320693D01*
X196968Y-321567D01*
X198184Y-322217D01*
X199504Y-322618D01*
X200876Y-322753D01*
X202248Y-322618D01*
X203568Y-322217D01*
X204784Y-321567D01*
X205850Y-320693D01*
X206724Y-319627D01*
X207374Y-318411D01*
X207775Y-317091D01*
X207910Y-315719D01*
X207775Y-314347D01*
X207374Y-313027D01*
X206724Y-311811D01*
X205850Y-310745D01*
X204784Y-309871D01*
X203568Y-309221D01*
X202248Y-308820D01*
X200876Y-308685D01*
D02*
G37*
G36*
X362408Y-325006D02*
X361706Y-325146D01*
X361415Y-325340D01*
X361030Y-325508D01*
X360645Y-325340D01*
X360354Y-325146D01*
X359652Y-325006D01*
X358950Y-325146D01*
X358354Y-325543D01*
X357957Y-326139D01*
X357817Y-326841D01*
X357957Y-327544D01*
X358354Y-328139D01*
X358950Y-328537D01*
X359652Y-328677D01*
X360354Y-328537D01*
X360645Y-328343D01*
X361030Y-328174D01*
X361415Y-328343D01*
X361706Y-328537D01*
X362408Y-328677D01*
X363110Y-328537D01*
X363706Y-328139D01*
X364104Y-327544D01*
X364243Y-326841D01*
X364104Y-326139D01*
X363706Y-325543D01*
X363110Y-325146D01*
X362408Y-325006D01*
D02*
G37*
G36*
X374114Y-326199D02*
X373412Y-326339D01*
X372817Y-326736D01*
X372656D01*
X372061Y-326339D01*
X371359Y-326199D01*
X370656Y-326339D01*
X370061Y-326736D01*
X369663Y-327332D01*
X369523Y-328034D01*
X369629Y-328563D01*
X369204Y-328881D01*
X368813Y-328619D01*
X368110Y-328480D01*
X367408Y-328619D01*
X366812Y-329017D01*
X366652D01*
X366057Y-328619D01*
X365354Y-328480D01*
X364652Y-328619D01*
X364057Y-329017D01*
X363659Y-329613D01*
X363519Y-330315D01*
X363659Y-331017D01*
X364057Y-331613D01*
X364652Y-332011D01*
X365354Y-332150D01*
X366057Y-332011D01*
X366347Y-331816D01*
X366732Y-331648D01*
X367117Y-331816D01*
X367408Y-332011D01*
X368110Y-332150D01*
X368813Y-332011D01*
X369408Y-331613D01*
X369806Y-331017D01*
X369946Y-330315D01*
X369840Y-329786D01*
X370265Y-329468D01*
X370656Y-329730D01*
X371359Y-329869D01*
X372061Y-329730D01*
X372656Y-329332D01*
X372817D01*
X373412Y-329730D01*
X374114Y-329869D01*
X374817Y-329730D01*
X375412Y-329332D01*
X375810Y-328736D01*
X375950Y-328034D01*
X375810Y-327332D01*
X375412Y-326736D01*
X374817Y-326339D01*
X374114Y-326199D01*
D02*
G37*
G36*
X75768Y-314588D02*
X74395Y-314723D01*
X73076Y-315124D01*
X71860Y-315774D01*
X70794Y-316648D01*
X69919Y-317714D01*
X69269Y-318930D01*
X68869Y-320250D01*
X68734Y-321622D01*
X68869Y-322994D01*
X69269Y-324314D01*
X69919Y-325530D01*
X70794Y-326596D01*
X71860Y-327470D01*
X73076Y-328120D01*
X74395Y-328521D01*
X75768Y-328656D01*
X77140Y-328521D01*
X78459Y-328120D01*
X79676Y-327470D01*
X80741Y-326596D01*
X81616Y-325530D01*
X82266Y-324314D01*
X82666Y-322994D01*
X82802Y-321622D01*
X82666Y-320250D01*
X82266Y-318930D01*
X81616Y-317714D01*
X80741Y-316648D01*
X79676Y-315774D01*
X78459Y-315124D01*
X77140Y-314723D01*
X75768Y-314588D01*
D02*
G37*
G36*
X356299Y-328480D02*
X355597Y-328619D01*
X355001Y-329017D01*
X354841D01*
X354246Y-328619D01*
X353543Y-328480D01*
X352841Y-328619D01*
X352246Y-329017D01*
X351848Y-329613D01*
X351708Y-330315D01*
X351848Y-331017D01*
X352246Y-331613D01*
X352841Y-332011D01*
X353543Y-332150D01*
X354246Y-332011D01*
X354841Y-331613D01*
X355001D01*
X355597Y-332011D01*
X356299Y-332150D01*
X357001Y-332011D01*
X357597Y-331613D01*
X357995Y-331017D01*
X358135Y-330315D01*
X357995Y-329613D01*
X357597Y-329017D01*
X357001Y-328619D01*
X356299Y-328480D01*
D02*
G37*
G36*
X58268Y-317593D02*
X57091Y-317709D01*
X55961Y-318052D01*
X54918Y-318609D01*
X54005Y-319359D01*
X53255Y-320272D01*
X52698Y-321315D01*
X52355Y-322446D01*
X52239Y-323622D01*
X52355Y-324798D01*
X52698Y-325929D01*
X53255Y-326972D01*
X54005Y-327885D01*
X54918Y-328635D01*
X55961Y-329192D01*
X57091Y-329535D01*
X58268Y-329651D01*
X59444Y-329535D01*
X60575Y-329192D01*
X61617Y-328635D01*
X62531Y-327885D01*
X63281Y-326972D01*
X63838Y-325929D01*
X64181Y-324798D01*
X64297Y-323622D01*
X64181Y-322446D01*
X63838Y-321315D01*
X63281Y-320272D01*
X62531Y-319359D01*
X61617Y-318609D01*
X60575Y-318052D01*
X59444Y-317709D01*
X58268Y-317593D01*
D02*
G37*
G36*
X390452Y-327766D02*
X389639Y-327928D01*
X388950Y-328388D01*
X388490Y-329077D01*
X388329Y-329890D01*
X388490Y-330703D01*
X388950Y-331392D01*
X389639Y-331852D01*
X390452Y-332014D01*
X391265Y-331852D01*
X391954Y-331392D01*
X392414Y-330703D01*
X392576Y-329890D01*
X392414Y-329077D01*
X391954Y-328388D01*
X391265Y-327928D01*
X390452Y-327766D01*
D02*
G37*
G36*
X311712D02*
X310899Y-327928D01*
X310210Y-328388D01*
X309750Y-329077D01*
X309589Y-329890D01*
X309750Y-330703D01*
X310210Y-331392D01*
X310899Y-331852D01*
X311712Y-332014D01*
X312525Y-331852D01*
X313214Y-331392D01*
X313674Y-330703D01*
X313836Y-329890D01*
X313674Y-329077D01*
X313214Y-328388D01*
X312525Y-327928D01*
X311712Y-327766D01*
D02*
G37*
G36*
X209842Y-328223D02*
X208666Y-328339D01*
X207535Y-328682D01*
X206493Y-329239D01*
X205579Y-329989D01*
X204830Y-330902D01*
X204272Y-331945D01*
X204187Y-332226D01*
X203687D01*
X203602Y-331945D01*
X203045Y-330902D01*
X202295Y-329989D01*
X201381Y-329239D01*
X200339Y-328682D01*
X199208Y-328339D01*
X198031Y-328223D01*
X196855Y-328339D01*
X195724Y-328682D01*
X194682Y-329239D01*
X193768Y-329989D01*
X193018Y-330902D01*
X192461Y-331945D01*
X192376Y-332226D01*
X191876D01*
X191791Y-331945D01*
X191233Y-330902D01*
X190484Y-329989D01*
X189570Y-329239D01*
X188528Y-328682D01*
X187397Y-328339D01*
X186221Y-328223D01*
X185044Y-328339D01*
X183913Y-328682D01*
X182871Y-329239D01*
X181957Y-329989D01*
X181208Y-330902D01*
X180650Y-331945D01*
X180482Y-332501D01*
X179959D01*
X179791Y-331945D01*
X179233Y-330902D01*
X178484Y-329989D01*
X177570Y-329239D01*
X176528Y-328682D01*
X175397Y-328339D01*
X174221Y-328223D01*
X173044Y-328339D01*
X171913Y-328682D01*
X170871Y-329239D01*
X169957Y-329989D01*
X169208Y-330902D01*
X168650Y-331945D01*
X168482Y-332501D01*
X167959D01*
X167791Y-331945D01*
X167233Y-330902D01*
X166484Y-329989D01*
X165570Y-329239D01*
X164528Y-328682D01*
X163397Y-328339D01*
X162221Y-328223D01*
X161044Y-328339D01*
X159913Y-328682D01*
X158871Y-329239D01*
X157957Y-329989D01*
X157208Y-330902D01*
X156650Y-331945D01*
X156307Y-333076D01*
X156191Y-334252D01*
X156307Y-335428D01*
X156650Y-336559D01*
X157208Y-337601D01*
X157957Y-338515D01*
X158871Y-339265D01*
X159913Y-339822D01*
X161044Y-340165D01*
X162221Y-340281D01*
X163397Y-340165D01*
X164528Y-339822D01*
X165570Y-339265D01*
X166484Y-338515D01*
X167233Y-337601D01*
X167791Y-336559D01*
X167959Y-336003D01*
X168482D01*
X168650Y-336559D01*
X169208Y-337601D01*
X169957Y-338515D01*
X170871Y-339265D01*
X171913Y-339822D01*
X173044Y-340165D01*
X174221Y-340281D01*
X175397Y-340165D01*
X176528Y-339822D01*
X177570Y-339265D01*
X178484Y-338515D01*
X179233Y-337601D01*
X179791Y-336559D01*
X179959Y-336003D01*
X180482D01*
X180650Y-336559D01*
X181208Y-337601D01*
X181957Y-338515D01*
X182871Y-339265D01*
X183913Y-339822D01*
X185044Y-340165D01*
X186221Y-340281D01*
X187397Y-340165D01*
X188528Y-339822D01*
X189570Y-339265D01*
X190484Y-338515D01*
X191233Y-337601D01*
X191791Y-336559D01*
X191876Y-336278D01*
X192376D01*
X192461Y-336559D01*
X193018Y-337601D01*
X193768Y-338515D01*
X194682Y-339265D01*
X195724Y-339822D01*
X196855Y-340165D01*
X198031Y-340281D01*
X199208Y-340165D01*
X200339Y-339822D01*
X201381Y-339265D01*
X202295Y-338515D01*
X203045Y-337601D01*
X203602Y-336559D01*
X203687Y-336278D01*
X204187D01*
X204272Y-336559D01*
X204830Y-337601D01*
X205579Y-338515D01*
X206493Y-339265D01*
X207535Y-339822D01*
X208666Y-340165D01*
X209842Y-340281D01*
X211019Y-340165D01*
X212150Y-339822D01*
X213192Y-339265D01*
X214106Y-338515D01*
X214856Y-337601D01*
X215413Y-336559D01*
X215756Y-335428D01*
X215872Y-334252D01*
X215756Y-333076D01*
X215413Y-331945D01*
X214856Y-330902D01*
X214106Y-329989D01*
X213192Y-329239D01*
X212150Y-328682D01*
X211019Y-328339D01*
X209842Y-328223D01*
D02*
G37*
G36*
X622677Y-331472D02*
X621975Y-331611D01*
X621379Y-332009D01*
X620982Y-332605D01*
X620842Y-333307D01*
X620982Y-334009D01*
X621379Y-334605D01*
X621975Y-335003D01*
X622677Y-335142D01*
X623380Y-335003D01*
X623975Y-334605D01*
X624373Y-334009D01*
X624512Y-333307D01*
X624373Y-332605D01*
X623975Y-332009D01*
X623380Y-331611D01*
X622677Y-331472D01*
D02*
G37*
G36*
X598959D02*
X598257Y-331611D01*
X597662Y-332009D01*
X597264Y-332605D01*
X597124Y-333307D01*
X597264Y-334009D01*
X597662Y-334605D01*
X598257Y-335003D01*
X598959Y-335142D01*
X599662Y-335003D01*
X600257Y-334605D01*
X600655Y-334009D01*
X600795Y-333307D01*
X600655Y-332605D01*
X600257Y-332009D01*
X599662Y-331611D01*
X598959Y-331472D01*
D02*
G37*
G36*
X552756Y-333992D02*
X552054Y-334131D01*
X551458Y-334529D01*
X551060Y-335124D01*
X550921Y-335827D01*
X551060Y-336529D01*
X551458Y-337124D01*
X552054Y-337522D01*
X552756Y-337662D01*
X553458Y-337522D01*
X554054Y-337124D01*
X554452Y-336529D01*
X554591Y-335827D01*
X554452Y-335124D01*
X554054Y-334529D01*
X553458Y-334131D01*
X552756Y-333992D01*
D02*
G37*
G36*
X505410Y-334201D02*
X504708Y-334341D01*
X504112Y-334739D01*
X503715Y-335334D01*
X503575Y-336036D01*
X503715Y-336739D01*
X504112Y-337334D01*
X504708Y-337732D01*
X505410Y-337872D01*
X506112Y-337732D01*
X506708Y-337334D01*
X507106Y-336739D01*
X507245Y-336036D01*
X507106Y-335334D01*
X506708Y-334739D01*
X506112Y-334341D01*
X505410Y-334201D01*
D02*
G37*
G36*
X544882Y-334385D02*
X544180Y-334525D01*
X543584Y-334923D01*
X543186Y-335518D01*
X543047Y-336221D01*
X543186Y-336923D01*
X543584Y-337518D01*
X544180Y-337916D01*
X544882Y-338056D01*
X545584Y-337916D01*
X546180Y-337518D01*
X546578Y-336923D01*
X546717Y-336221D01*
X546578Y-335518D01*
X546180Y-334923D01*
X545584Y-334525D01*
X544882Y-334385D01*
D02*
G37*
G36*
X521654D02*
X520951Y-334525D01*
X520356Y-334923D01*
X519958Y-335518D01*
X519818Y-336221D01*
X519958Y-336923D01*
X520356Y-337518D01*
X520951Y-337916D01*
X521654Y-338056D01*
X522356Y-337916D01*
X522951Y-337518D01*
X523349Y-336923D01*
X523489Y-336221D01*
X523349Y-335518D01*
X522951Y-334923D01*
X522356Y-334525D01*
X521654Y-334385D01*
D02*
G37*
G36*
X513386D02*
X512683Y-334525D01*
X512088Y-334923D01*
X511690Y-335518D01*
X511551Y-336221D01*
X511690Y-336923D01*
X512088Y-337518D01*
X512683Y-337916D01*
X513386Y-338056D01*
X514088Y-337916D01*
X514684Y-337518D01*
X515081Y-336923D01*
X515221Y-336221D01*
X515081Y-335518D01*
X514684Y-334923D01*
X514088Y-334525D01*
X513386Y-334385D01*
D02*
G37*
G36*
X27559Y-335566D02*
X26857Y-335706D01*
X26261Y-336104D01*
X25864Y-336699D01*
X25724Y-337402D01*
X25864Y-338104D01*
X26261Y-338699D01*
X26857Y-339097D01*
X27559Y-339237D01*
X28261Y-339097D01*
X28857Y-338699D01*
X29255Y-338104D01*
X29394Y-337402D01*
X29255Y-336699D01*
X28857Y-336104D01*
X28261Y-335706D01*
X27559Y-335566D01*
D02*
G37*
G36*
X530315Y-337141D02*
X529613Y-337281D01*
X529017Y-337679D01*
X528619Y-338274D01*
X528480Y-338976D01*
X528619Y-339679D01*
X529017Y-340274D01*
X529613Y-340672D01*
X530315Y-340812D01*
X531017Y-340672D01*
X531613Y-340274D01*
X532011Y-339679D01*
X532150Y-338976D01*
X532011Y-338274D01*
X531613Y-337679D01*
X531017Y-337281D01*
X530315Y-337141D01*
D02*
G37*
G36*
X453193Y-327117D02*
X451839Y-327251D01*
X450537Y-327646D01*
X449338Y-328287D01*
X448286Y-329150D01*
X447423Y-330201D01*
X446782Y-331401D01*
X446387Y-332703D01*
X446254Y-334056D01*
X446387Y-335410D01*
X446782Y-336712D01*
X447423Y-337912D01*
X448286Y-338963D01*
X449338Y-339826D01*
X450537Y-340467D01*
X451839Y-340862D01*
X453193Y-340995D01*
X454546Y-340862D01*
X455848Y-340467D01*
X457048Y-339826D01*
X458099Y-338963D01*
X458962Y-337912D01*
X459604Y-336712D01*
X459998Y-335410D01*
X460132Y-334056D01*
X459998Y-332703D01*
X459604Y-331401D01*
X458962Y-330201D01*
X458099Y-329150D01*
X457048Y-328287D01*
X455848Y-327646D01*
X454546Y-327251D01*
X453193Y-327117D01*
D02*
G37*
G36*
X256693D02*
X255339Y-327251D01*
X254037Y-327646D01*
X252838Y-328287D01*
X251786Y-329150D01*
X250923Y-330201D01*
X250282Y-331401D01*
X249887Y-332703D01*
X249754Y-334056D01*
X249887Y-335410D01*
X250282Y-336712D01*
X250923Y-337912D01*
X251786Y-338963D01*
X252838Y-339826D01*
X254037Y-340467D01*
X255339Y-340862D01*
X256693Y-340995D01*
X258047Y-340862D01*
X259348Y-340467D01*
X260548Y-339826D01*
X261599Y-338963D01*
X262462Y-337912D01*
X263104Y-336712D01*
X263498Y-335410D01*
X263632Y-334056D01*
X263498Y-332703D01*
X263104Y-331401D01*
X262462Y-330201D01*
X261599Y-329150D01*
X260548Y-328287D01*
X259348Y-327646D01*
X258047Y-327251D01*
X256693Y-327117D01*
D02*
G37*
G36*
X561024Y-338322D02*
X560321Y-338462D01*
X559726Y-338860D01*
X559328Y-339455D01*
X559188Y-340158D01*
X559328Y-340860D01*
X559726Y-341455D01*
X560321Y-341853D01*
X561024Y-341993D01*
X561726Y-341853D01*
X562321Y-341455D01*
X562719Y-340860D01*
X562859Y-340158D01*
X562719Y-339455D01*
X562321Y-338860D01*
X561726Y-338462D01*
X561024Y-338322D01*
D02*
G37*
G36*
X582058Y-320039D02*
X580331Y-320175D01*
X578648Y-320579D01*
X577048Y-321241D01*
X575572Y-322146D01*
X574255Y-323271D01*
X573131Y-324587D01*
X572226Y-326063D01*
X571564Y-327663D01*
X571159Y-329347D01*
X571024Y-331073D01*
X571159Y-332799D01*
X571564Y-334483D01*
X572226Y-336082D01*
X573131Y-337559D01*
X574255Y-338875D01*
X575572Y-340000D01*
X577048Y-340904D01*
X578648Y-341567D01*
X580331Y-341971D01*
X582058Y-342107D01*
X583784Y-341971D01*
X585467Y-341567D01*
X587067Y-340904D01*
X588543Y-340000D01*
X589860Y-338875D01*
X590984Y-337559D01*
X591889Y-336082D01*
X592552Y-334483D01*
X592956Y-332799D01*
X593091Y-331073D01*
X592956Y-329347D01*
X592552Y-327663D01*
X591889Y-326063D01*
X590984Y-324587D01*
X589860Y-323271D01*
X588543Y-322146D01*
X587067Y-321241D01*
X585467Y-320579D01*
X583784Y-320175D01*
X582058Y-320039D01*
D02*
G37*
G36*
X479695D02*
X477969Y-320175D01*
X476286Y-320579D01*
X474686Y-321241D01*
X473210Y-322146D01*
X471893Y-323271D01*
X470769Y-324587D01*
X469864Y-326063D01*
X469201Y-327663D01*
X468797Y-329347D01*
X468661Y-331073D01*
X468797Y-332799D01*
X469201Y-334483D01*
X469864Y-336082D01*
X470769Y-337559D01*
X471893Y-338875D01*
X473210Y-340000D01*
X474686Y-340904D01*
X476286Y-341567D01*
X477969Y-341971D01*
X479695Y-342107D01*
X481421Y-341971D01*
X483105Y-341567D01*
X484705Y-340904D01*
X486181Y-340000D01*
X487498Y-338875D01*
X488622Y-337559D01*
X489527Y-336082D01*
X490189Y-334483D01*
X490593Y-332799D01*
X490729Y-331073D01*
X490593Y-329347D01*
X490189Y-327663D01*
X489527Y-326063D01*
X488622Y-324587D01*
X487498Y-323271D01*
X486181Y-322146D01*
X484705Y-321241D01*
X483105Y-320579D01*
X481421Y-320175D01*
X479695Y-320039D01*
D02*
G37*
G36*
X540551Y-339110D02*
X539849Y-339249D01*
X539254Y-339647D01*
X538856Y-340243D01*
X538716Y-340945D01*
X538856Y-341647D01*
X539254Y-342243D01*
X539849Y-342640D01*
X540551Y-342780D01*
X541254Y-342640D01*
X541849Y-342243D01*
X542247Y-341647D01*
X542386Y-340945D01*
X542247Y-340243D01*
X541849Y-339647D01*
X541254Y-339249D01*
X540551Y-339110D01*
D02*
G37*
G36*
X-23622Y-333795D02*
X-24324Y-333934D01*
X-24920Y-334332D01*
X-25318Y-334928D01*
X-25457Y-335630D01*
X-25318Y-336332D01*
X-24920Y-336928D01*
X-24324Y-337326D01*
X-24234Y-337344D01*
Y-337853D01*
X-24324Y-337871D01*
X-24920Y-338269D01*
X-25318Y-338865D01*
X-25457Y-339567D01*
X-25318Y-340269D01*
X-25032Y-340696D01*
X-24958Y-341043D01*
X-25032Y-341391D01*
X-25318Y-341817D01*
X-25457Y-342520D01*
X-25318Y-343222D01*
X-24920Y-343817D01*
X-24324Y-344215D01*
X-23622Y-344355D01*
X-22920Y-344215D01*
X-22324Y-343817D01*
X-21926Y-343222D01*
X-21787Y-342520D01*
X-21926Y-341817D01*
X-22212Y-341391D01*
X-22286Y-341043D01*
X-22212Y-340696D01*
X-21926Y-340269D01*
X-21787Y-339567D01*
X-21926Y-338865D01*
X-22324Y-338269D01*
X-22920Y-337871D01*
X-23010Y-337853D01*
Y-337344D01*
X-22920Y-337326D01*
X-22324Y-336928D01*
X-21926Y-336332D01*
X-21787Y-335630D01*
X-21926Y-334928D01*
X-22324Y-334332D01*
X-22920Y-333934D01*
X-23622Y-333795D01*
D02*
G37*
G36*
X380807Y-344309D02*
X380105Y-344449D01*
X379542Y-344825D01*
X379396Y-344887D01*
X379069D01*
X378923Y-344825D01*
X378360Y-344449D01*
X377658Y-344309D01*
X376956Y-344449D01*
X376360Y-344847D01*
X376187Y-345106D01*
X375585D01*
X375412Y-344847D01*
X374817Y-344449D01*
X374114Y-344309D01*
X373412Y-344449D01*
X372817Y-344847D01*
X372656D01*
X372061Y-344449D01*
X371359Y-344309D01*
X370656Y-344449D01*
X370061Y-344847D01*
X369663Y-345442D01*
X369645Y-345533D01*
X369135D01*
X369117Y-345442D01*
X368719Y-344847D01*
X368124Y-344449D01*
X367422Y-344309D01*
X366719Y-344449D01*
X366429Y-344643D01*
X366044Y-344812D01*
X365659Y-344643D01*
X365368Y-344449D01*
X364666Y-344309D01*
X363963Y-344449D01*
X363368Y-344847D01*
X362970Y-345442D01*
X362952Y-345533D01*
X362442D01*
X362424Y-345442D01*
X362026Y-344847D01*
X361431Y-344449D01*
X360729Y-344309D01*
X360026Y-344449D01*
X359431Y-344847D01*
X359270D01*
X358675Y-344449D01*
X357973Y-344309D01*
X357270Y-344449D01*
X356675Y-344847D01*
X356277Y-345442D01*
X356259Y-345533D01*
X355749D01*
X355731Y-345442D01*
X355333Y-344847D01*
X354738Y-344449D01*
X354036Y-344309D01*
X353333Y-344449D01*
X352738Y-344847D01*
X352577D01*
X351982Y-344449D01*
X351280Y-344309D01*
X350577Y-344449D01*
X349982Y-344847D01*
X349584Y-345442D01*
X349445Y-346144D01*
X349584Y-346847D01*
X349982Y-347442D01*
X350577Y-347840D01*
X351280Y-347980D01*
X351982Y-347840D01*
X352577Y-347442D01*
X352738D01*
X353333Y-347840D01*
X354036Y-347980D01*
X354738Y-347840D01*
X355333Y-347442D01*
X355731Y-346847D01*
X355749Y-346756D01*
X356259D01*
X356277Y-346847D01*
X356675Y-347442D01*
X357270Y-347840D01*
X357973Y-347980D01*
X358675Y-347840D01*
X359270Y-347442D01*
X359431D01*
X360026Y-347840D01*
X360729Y-347980D01*
X361431Y-347840D01*
X362026Y-347442D01*
X362424Y-346847D01*
X362442Y-346756D01*
X362952D01*
X362970Y-346847D01*
X363368Y-347442D01*
X363963Y-347840D01*
X364666Y-347980D01*
X365368Y-347840D01*
X365659Y-347646D01*
X366044Y-347477D01*
X366429Y-347646D01*
X366719Y-347840D01*
X367422Y-347980D01*
X368124Y-347840D01*
X368719Y-347442D01*
X369117Y-346847D01*
X369135Y-346756D01*
X369645D01*
X369663Y-346847D01*
X370061Y-347442D01*
X370656Y-347840D01*
X371359Y-347980D01*
X372061Y-347840D01*
X372656Y-347442D01*
X372817D01*
X373412Y-347840D01*
X374114Y-347980D01*
X374817Y-347840D01*
X375412Y-347442D01*
X375585Y-347183D01*
X376187D01*
X376360Y-347442D01*
X376956Y-347840D01*
X377658Y-347980D01*
X378360Y-347840D01*
X378923Y-347464D01*
X379069Y-347402D01*
X379396D01*
X379542Y-347464D01*
X380105Y-347840D01*
X380807Y-347980D01*
X381510Y-347840D01*
X382105Y-347442D01*
X382503Y-346847D01*
X382643Y-346144D01*
X382503Y-345442D01*
X382105Y-344847D01*
X381510Y-344449D01*
X380807Y-344309D01*
D02*
G37*
G36*
X623228Y-341472D02*
X622526Y-341612D01*
X621931Y-342009D01*
X621533Y-342605D01*
X621393Y-343307D01*
X621533Y-344009D01*
X621931Y-344605D01*
X622526Y-345003D01*
X623228Y-345142D01*
X623931Y-345003D01*
X624526Y-344605D01*
X624924Y-344009D01*
X625064Y-343307D01*
X624924Y-342605D01*
X624526Y-342009D01*
X623931Y-341612D01*
X623228Y-341472D01*
D02*
G37*
G36*
X598819D02*
X598117Y-341612D01*
X597521Y-342009D01*
X597123Y-342605D01*
X596984Y-343307D01*
X597123Y-344009D01*
X597521Y-344605D01*
X598117Y-345003D01*
X598819Y-345142D01*
X599521Y-345003D01*
X600117Y-344605D01*
X600515Y-344009D01*
X600654Y-343307D01*
X600515Y-342605D01*
X600117Y-342009D01*
X599521Y-341612D01*
X598819Y-341472D01*
D02*
G37*
G36*
X4331Y-342653D02*
X3628Y-342793D01*
X3033Y-343191D01*
X2635Y-343786D01*
X2495Y-344488D01*
X2635Y-345191D01*
X3033Y-345786D01*
X3628Y-346184D01*
X4331Y-346323D01*
X5033Y-346184D01*
X5628Y-345786D01*
X6026Y-345191D01*
X6166Y-344488D01*
X6026Y-343786D01*
X5628Y-343191D01*
X5033Y-342793D01*
X4331Y-342653D01*
D02*
G37*
G36*
X29543Y-343379D02*
X28841Y-343519D01*
X28245Y-343917D01*
X27847Y-344512D01*
X27708Y-345214D01*
X27847Y-345917D01*
X28245Y-346512D01*
X28841Y-346910D01*
X29543Y-347050D01*
X30245Y-346910D01*
X30841Y-346512D01*
X31238Y-345917D01*
X31378Y-345214D01*
X31238Y-344512D01*
X30841Y-343917D01*
X30245Y-343519D01*
X29543Y-343379D01*
D02*
G37*
G36*
X142126Y-346196D02*
X141424Y-346336D01*
X140828Y-346734D01*
X140430Y-347329D01*
X140291Y-348031D01*
X140430Y-348734D01*
X140828Y-349329D01*
X141424Y-349727D01*
X142126Y-349867D01*
X142828Y-349727D01*
X143424Y-349329D01*
X143822Y-348734D01*
X143961Y-348031D01*
X143822Y-347329D01*
X143424Y-346734D01*
X142828Y-346336D01*
X142126Y-346196D01*
D02*
G37*
G36*
X26772Y-346984D02*
X26069Y-347123D01*
X25474Y-347521D01*
X25076Y-348117D01*
X24936Y-348819D01*
X25076Y-349521D01*
X25474Y-350117D01*
X26069Y-350515D01*
X26772Y-350654D01*
X27474Y-350515D01*
X28069Y-350117D01*
X28467Y-349521D01*
X28607Y-348819D01*
X28467Y-348117D01*
X28069Y-347521D01*
X27474Y-347123D01*
X26772Y-346984D01*
D02*
G37*
G36*
X12598Y-347377D02*
X11896Y-347517D01*
X11301Y-347915D01*
X10903Y-348510D01*
X10763Y-349213D01*
X10903Y-349915D01*
X11301Y-350510D01*
X11896Y-350908D01*
X12598Y-351048D01*
X13301Y-350908D01*
X13896Y-350510D01*
X14294Y-349915D01*
X14434Y-349213D01*
X14294Y-348510D01*
X13896Y-347915D01*
X13301Y-347517D01*
X12598Y-347377D01*
D02*
G37*
G36*
X-18601Y-347574D02*
X-19304Y-347714D01*
X-19899Y-348112D01*
X-20297Y-348707D01*
X-20437Y-349409D01*
X-20297Y-350112D01*
X-19899Y-350707D01*
X-19304Y-351105D01*
X-18601Y-351244D01*
X-17899Y-351105D01*
X-17304Y-350707D01*
X-16906Y-350112D01*
X-16766Y-349409D01*
X-16906Y-348707D01*
X-17304Y-348112D01*
X-17899Y-347714D01*
X-18601Y-347574D01*
D02*
G37*
G36*
X141587Y-350326D02*
X140885Y-350466D01*
X140290Y-350864D01*
X139892Y-351459D01*
X139752Y-352161D01*
X139892Y-352864D01*
X140290Y-353459D01*
X140885Y-353857D01*
X141587Y-353997D01*
X142290Y-353857D01*
X142885Y-353459D01*
X143283Y-352864D01*
X143423Y-352161D01*
X143283Y-351459D01*
X142885Y-350864D01*
X142290Y-350466D01*
X141587Y-350326D01*
D02*
G37*
G36*
X-1181Y-350995D02*
X-1883Y-351135D01*
X-2479Y-351533D01*
X-2877Y-352128D01*
X-3016Y-352831D01*
X-2877Y-353533D01*
X-2479Y-354129D01*
X-1883Y-354526D01*
X-1181Y-354666D01*
X-479Y-354526D01*
X117Y-354129D01*
X514Y-353533D01*
X654Y-352831D01*
X514Y-352128D01*
X117Y-351533D01*
X-479Y-351135D01*
X-1181Y-350995D01*
D02*
G37*
G36*
X622753Y-351472D02*
X622051Y-351611D01*
X621456Y-352009D01*
X621058Y-352605D01*
X620918Y-353307D01*
X621058Y-354009D01*
X621456Y-354605D01*
X622051Y-355003D01*
X622753Y-355142D01*
X623456Y-355003D01*
X624051Y-354605D01*
X624449Y-354009D01*
X624589Y-353307D01*
X624449Y-352605D01*
X624051Y-352009D01*
X623456Y-351611D01*
X622753Y-351472D01*
D02*
G37*
G36*
X157480Y-356826D02*
X156778Y-356966D01*
X156496Y-357154D01*
X156214Y-356966D01*
X155512Y-356826D01*
X154809Y-356966D01*
X154528Y-357154D01*
X154246Y-356966D01*
X153543Y-356826D01*
X152841Y-356966D01*
X152246Y-357364D01*
X151848Y-357959D01*
X151708Y-358661D01*
X151848Y-359364D01*
X152246Y-359959D01*
X152286Y-359986D01*
Y-360486D01*
X152246Y-360513D01*
X151848Y-361109D01*
X151708Y-361811D01*
X151848Y-362513D01*
X152246Y-363109D01*
X152841Y-363507D01*
X153543Y-363646D01*
X154246Y-363507D01*
X154528Y-363318D01*
X154809Y-363507D01*
X155512Y-363646D01*
X156214Y-363507D01*
X156496Y-363318D01*
X156778Y-363507D01*
X157480Y-363646D01*
X158183Y-363507D01*
X158778Y-363109D01*
X159176Y-362513D01*
X159316Y-361811D01*
X159176Y-361109D01*
X158778Y-360513D01*
X158738Y-360486D01*
Y-359986D01*
X158778Y-359959D01*
X159176Y-359364D01*
X159316Y-358661D01*
X159176Y-357959D01*
X158778Y-357364D01*
X158183Y-356966D01*
X157480Y-356826D01*
D02*
G37*
G36*
X449150Y-353997D02*
X448448Y-354137D01*
X447853Y-354535D01*
X447455Y-355130D01*
X447315Y-355832D01*
X447455Y-356535D01*
X447853Y-357130D01*
X448448Y-357528D01*
X449150Y-357668D01*
X449853Y-357528D01*
X450448Y-357130D01*
X450846Y-356535D01*
X450985Y-355832D01*
X450846Y-355130D01*
X450448Y-354535D01*
X449853Y-354137D01*
X449150Y-353997D01*
D02*
G37*
G36*
X561330Y-354264D02*
X560628Y-354404D01*
X560032Y-354802D01*
X559635Y-355397D01*
X559495Y-356099D01*
X559635Y-356802D01*
X560032Y-357397D01*
X560628Y-357795D01*
X561330Y-357935D01*
X562032Y-357795D01*
X562628Y-357397D01*
X563026Y-356802D01*
X563165Y-356099D01*
X563026Y-355397D01*
X562628Y-354802D01*
X562032Y-354404D01*
X561330Y-354264D01*
D02*
G37*
G36*
X533931Y-354461D02*
X533228Y-354601D01*
X532633Y-354999D01*
X532235Y-355594D01*
X532095Y-356296D01*
X532235Y-356999D01*
X532633Y-357594D01*
X533228Y-357992D01*
X533931Y-358132D01*
X534633Y-357992D01*
X535228Y-357594D01*
X535626Y-356999D01*
X535766Y-356296D01*
X535626Y-355594D01*
X535228Y-354999D01*
X534633Y-354601D01*
X533931Y-354461D01*
D02*
G37*
G36*
X493234Y-354784D02*
X492532Y-354924D01*
X491936Y-355322D01*
X491538Y-355918D01*
X491399Y-356620D01*
X491538Y-357322D01*
X491936Y-357917D01*
X492532Y-358315D01*
X493234Y-358455D01*
X493936Y-358315D01*
X494532Y-357917D01*
X494930Y-357322D01*
X495069Y-356620D01*
X494930Y-355918D01*
X494532Y-355322D01*
X493936Y-354924D01*
X493234Y-354784D01*
D02*
G37*
G36*
X579072Y-354855D02*
X578370Y-354994D01*
X577774Y-355392D01*
X577376Y-355988D01*
X577237Y-356690D01*
X577376Y-357392D01*
X577774Y-357988D01*
X578370Y-358385D01*
X579072Y-358525D01*
X579774Y-358385D01*
X580370Y-357988D01*
X580767Y-357392D01*
X580907Y-356690D01*
X580767Y-355988D01*
X580370Y-355392D01*
X579774Y-354994D01*
X579072Y-354855D01*
D02*
G37*
G36*
X415623Y-356556D02*
X414920Y-356696D01*
X414325Y-357094D01*
X413927Y-357689D01*
X413788Y-358391D01*
X413927Y-359094D01*
X414325Y-359689D01*
X414920Y-360087D01*
X415623Y-360227D01*
X416325Y-360087D01*
X416921Y-359689D01*
X417318Y-359094D01*
X417458Y-358391D01*
X417318Y-357689D01*
X416921Y-357094D01*
X416325Y-356696D01*
X415623Y-356556D01*
D02*
G37*
G36*
X543698Y-356823D02*
X542996Y-356963D01*
X542400Y-357361D01*
X542002Y-357956D01*
X541863Y-358659D01*
X542002Y-359361D01*
X542400Y-359956D01*
X542996Y-360354D01*
X543698Y-360494D01*
X544400Y-360354D01*
X544996Y-359956D01*
X545393Y-359361D01*
X545533Y-358659D01*
X545393Y-357956D01*
X544996Y-357361D01*
X544400Y-356963D01*
X543698Y-356823D01*
D02*
G37*
G36*
X499525Y-357020D02*
X498823Y-357160D01*
X498228Y-357558D01*
X497830Y-358153D01*
X497690Y-358855D01*
X497830Y-359558D01*
X498228Y-360153D01*
X498823Y-360551D01*
X499525Y-360691D01*
X500228Y-360551D01*
X500823Y-360153D01*
X501221Y-359558D01*
X501361Y-358855D01*
X501221Y-358153D01*
X500823Y-357558D01*
X500228Y-357160D01*
X499525Y-357020D01*
D02*
G37*
G36*
X460678Y-357344D02*
X459975Y-357483D01*
X459380Y-357881D01*
X458982Y-358476D01*
X458842Y-359179D01*
X458982Y-359881D01*
X459380Y-360477D01*
X459975Y-360874D01*
X460678Y-361014D01*
X461380Y-360874D01*
X461975Y-360477D01*
X462373Y-359881D01*
X462513Y-359179D01*
X462373Y-358476D01*
X461975Y-357881D01*
X461380Y-357483D01*
X460678Y-357344D01*
D02*
G37*
G36*
X198392Y-365007D02*
X197690Y-365146D01*
X197094Y-365544D01*
X196697Y-366140D01*
X196557Y-366842D01*
X196697Y-367544D01*
X197094Y-368140D01*
X197343Y-368306D01*
X197148Y-368777D01*
X196701Y-368688D01*
X195999Y-368828D01*
X195403Y-369225D01*
X195005Y-369821D01*
X194866Y-370523D01*
X195005Y-371225D01*
X195403Y-371821D01*
X195999Y-372219D01*
X196701Y-372358D01*
X197403Y-372219D01*
X197998Y-371821D01*
X198396Y-371225D01*
X198536Y-370523D01*
X198396Y-369821D01*
X197998Y-369225D01*
X197750Y-369059D01*
X197945Y-368588D01*
X198392Y-368677D01*
X199094Y-368537D01*
X199690Y-368140D01*
X200088Y-367544D01*
X200227Y-366842D01*
X200088Y-366140D01*
X199690Y-365544D01*
X199094Y-365146D01*
X198392Y-365007D01*
D02*
G37*
G36*
X241929Y-372820D02*
X241227Y-372960D01*
X240631Y-373357D01*
X240234Y-373953D01*
X240215Y-374043D01*
X239706D01*
X239688Y-373953D01*
X239290Y-373357D01*
X238695Y-372960D01*
X237992Y-372820D01*
X237290Y-372960D01*
X236694Y-373357D01*
X236297Y-373953D01*
X236157Y-374655D01*
X236297Y-375357D01*
X236694Y-375953D01*
X237290Y-376351D01*
X237992Y-376490D01*
X238695Y-376351D01*
X239290Y-375953D01*
X239688Y-375357D01*
X239706Y-375267D01*
X240215D01*
X240234Y-375357D01*
X240631Y-375953D01*
X241227Y-376351D01*
X241929Y-376490D01*
X242632Y-376351D01*
X243227Y-375953D01*
X243625Y-375357D01*
X243764Y-374655D01*
X243625Y-373953D01*
X243227Y-373357D01*
X242632Y-372960D01*
X241929Y-372820D01*
D02*
G37*
G36*
X210433D02*
X209731Y-372960D01*
X209135Y-373357D01*
X208737Y-373953D01*
X208719Y-374043D01*
X208210D01*
X208192Y-373953D01*
X207794Y-373357D01*
X207198Y-372960D01*
X206496Y-372820D01*
X205794Y-372960D01*
X205198Y-373357D01*
X204801Y-373953D01*
X204661Y-374655D01*
X204801Y-375357D01*
X205198Y-375953D01*
X205794Y-376351D01*
X206496Y-376490D01*
X207198Y-376351D01*
X207794Y-375953D01*
X208192Y-375357D01*
X208210Y-375267D01*
X208719D01*
X208737Y-375357D01*
X209135Y-375953D01*
X209731Y-376351D01*
X210433Y-376490D01*
X211135Y-376351D01*
X211731Y-375953D01*
X212129Y-375357D01*
X212268Y-374655D01*
X212129Y-373953D01*
X211731Y-373357D01*
X211135Y-372960D01*
X210433Y-372820D01*
D02*
G37*
G36*
X218445Y-372272D02*
X217743Y-372412D01*
X217147Y-372810D01*
X216749Y-373405D01*
X216610Y-374108D01*
X216749Y-374810D01*
X217147Y-375405D01*
X217743Y-375803D01*
X218445Y-375943D01*
X219147Y-375803D01*
X219743Y-375405D01*
X220141Y-374810D01*
X220280Y-374108D01*
X220141Y-373405D01*
X219743Y-372810D01*
X219147Y-372412D01*
X218445Y-372272D01*
D02*
G37*
G36*
X269502Y-372456D02*
X268800Y-372595D01*
X268205Y-372993D01*
X267807Y-373589D01*
X267667Y-374291D01*
X267807Y-374993D01*
X268205Y-375589D01*
X268800Y-375987D01*
X269502Y-376126D01*
X270205Y-375987D01*
X270800Y-375589D01*
X271159Y-375051D01*
X271393Y-375038D01*
X271679Y-375104D01*
X271730Y-375357D01*
X272128Y-375953D01*
X272723Y-376351D01*
X273425Y-376490D01*
X274128Y-376351D01*
X274723Y-375953D01*
X275121Y-375357D01*
X275260Y-374655D01*
X275121Y-373953D01*
X274723Y-373357D01*
X274128Y-372960D01*
X273425Y-372820D01*
X272723Y-372960D01*
X272128Y-373357D01*
X271769Y-373895D01*
X271535Y-373908D01*
X271248Y-373842D01*
X271198Y-373589D01*
X270800Y-372993D01*
X270205Y-372595D01*
X269502Y-372456D01*
D02*
G37*
G36*
X253655Y-372586D02*
X252953Y-372726D01*
X252357Y-373123D01*
X251959Y-373719D01*
X251820Y-374421D01*
X251959Y-375123D01*
X252357Y-375719D01*
X252953Y-376117D01*
X253655Y-376256D01*
X254357Y-376117D01*
X254953Y-375719D01*
X255436D01*
X255592Y-375953D01*
X256187Y-376351D01*
X256890Y-376490D01*
X257592Y-376351D01*
X258188Y-375953D01*
X258585Y-375357D01*
X258725Y-374655D01*
X258585Y-373953D01*
X258188Y-373357D01*
X257592Y-372960D01*
X256890Y-372820D01*
X256187Y-372960D01*
X255592Y-373357D01*
X255109D01*
X254953Y-373123D01*
X254357Y-372726D01*
X253655Y-372586D01*
D02*
G37*
G36*
X222638Y-372820D02*
X221936Y-372960D01*
X221340Y-373357D01*
X220942Y-373953D01*
X220802Y-374655D01*
X220942Y-375357D01*
X221340Y-375953D01*
X221936Y-376351D01*
X222638Y-376490D01*
X223340Y-376351D01*
X223936Y-375953D01*
X224333Y-375357D01*
X224473Y-374655D01*
X224333Y-373953D01*
X223936Y-373357D01*
X223340Y-372960D01*
X222638Y-372820D01*
D02*
G37*
G36*
X190354Y-375576D02*
X189652Y-375715D01*
X189057Y-376113D01*
X188659Y-376709D01*
X188519Y-377411D01*
X188659Y-378113D01*
X189057Y-378709D01*
X189652Y-379107D01*
X190354Y-379246D01*
X191057Y-379107D01*
X191652Y-378709D01*
X192050Y-378113D01*
X192190Y-377411D01*
X192050Y-376709D01*
X191652Y-376113D01*
X191057Y-375715D01*
X190354Y-375576D01*
D02*
G37*
G36*
X178543D02*
X177841Y-375715D01*
X177246Y-376113D01*
X176848Y-376709D01*
X176708Y-377411D01*
X176848Y-378113D01*
X177246Y-378709D01*
X177841Y-379107D01*
X178543Y-379246D01*
X179246Y-379107D01*
X179841Y-378709D01*
X180239Y-378113D01*
X180379Y-377411D01*
X180239Y-376709D01*
X179841Y-376113D01*
X179246Y-375715D01*
X178543Y-375576D01*
D02*
G37*
G36*
X158661Y-384631D02*
X157959Y-384771D01*
X157677Y-384959D01*
X157395Y-384771D01*
X156693Y-384631D01*
X155991Y-384771D01*
X155709Y-384959D01*
X155427Y-384771D01*
X154724Y-384631D01*
X154022Y-384771D01*
X153427Y-385168D01*
X153029Y-385764D01*
X152889Y-386466D01*
X153029Y-387169D01*
X153427Y-387764D01*
X153467Y-387791D01*
Y-388291D01*
X153427Y-388318D01*
X153029Y-388913D01*
X152889Y-389616D01*
X153029Y-390318D01*
X153427Y-390914D01*
X154022Y-391311D01*
X154724Y-391451D01*
X155427Y-391311D01*
X155709Y-391123D01*
X155991Y-391311D01*
X156693Y-391451D01*
X157395Y-391311D01*
X157677Y-391123D01*
X157959Y-391311D01*
X158661Y-391451D01*
X159364Y-391311D01*
X159959Y-390914D01*
X160357Y-390318D01*
X160497Y-389616D01*
X160357Y-388913D01*
X159959Y-388318D01*
X159919Y-388291D01*
Y-387791D01*
X159959Y-387764D01*
X160357Y-387169D01*
X160497Y-386466D01*
X160357Y-385764D01*
X159959Y-385168D01*
X159364Y-384771D01*
X158661Y-384631D01*
D02*
G37*
G36*
X232480Y-385418D02*
X231778Y-385558D01*
X231215Y-385934D01*
X231069Y-385996D01*
X230743D01*
X230596Y-385934D01*
X230033Y-385558D01*
X229331Y-385418D01*
X228628Y-385558D01*
X228033Y-385956D01*
X227635Y-386551D01*
X227496Y-387253D01*
X227635Y-387956D01*
X228033Y-388551D01*
X228628Y-388949D01*
X229331Y-389089D01*
X230033Y-388949D01*
X230596Y-388573D01*
X230743Y-388511D01*
X231069D01*
X231215Y-388573D01*
X231778Y-388949D01*
X232480Y-389089D01*
X233183Y-388949D01*
X233778Y-388551D01*
X234176Y-387956D01*
X234316Y-387253D01*
X234176Y-386551D01*
X233778Y-385956D01*
X233183Y-385558D01*
X232480Y-385418D01*
D02*
G37*
G36*
X215945D02*
X215243Y-385558D01*
X214680Y-385934D01*
X214533Y-385996D01*
X214207D01*
X214060Y-385934D01*
X213498Y-385558D01*
X212795Y-385418D01*
X212093Y-385558D01*
X211498Y-385956D01*
X211100Y-386551D01*
X210960Y-387253D01*
X211100Y-387956D01*
X211498Y-388551D01*
X212093Y-388949D01*
X212795Y-389089D01*
X213498Y-388949D01*
X214060Y-388573D01*
X214207Y-388511D01*
X214533D01*
X214680Y-388573D01*
X215243Y-388949D01*
X215945Y-389089D01*
X216647Y-388949D01*
X217243Y-388551D01*
X217640Y-387956D01*
X217780Y-387253D01*
X217640Y-386551D01*
X217243Y-385956D01*
X216647Y-385558D01*
X215945Y-385418D01*
D02*
G37*
G36*
X265158D02*
X264455Y-385558D01*
X263890Y-385935D01*
X263746Y-385999D01*
X263331D01*
X263304Y-385958D01*
X262708Y-385560D01*
X262006Y-385420D01*
X261304Y-385560D01*
X260708Y-385958D01*
X260311Y-386553D01*
X260171Y-387255D01*
X260311Y-387958D01*
X260708Y-388553D01*
X261304Y-388951D01*
X262006Y-389090D01*
X262708Y-388951D01*
X263273Y-388574D01*
X263417Y-388510D01*
X263832D01*
X263860Y-388551D01*
X264455Y-388949D01*
X265158Y-389089D01*
X265860Y-388949D01*
X266455Y-388551D01*
X266853Y-387956D01*
X266993Y-387253D01*
X266853Y-386551D01*
X266455Y-385956D01*
X265860Y-385558D01*
X265158Y-385418D01*
D02*
G37*
G36*
X246339Y-385140D02*
X245636Y-385279D01*
X245041Y-385677D01*
X244643Y-386273D01*
X244503Y-386975D01*
X244643Y-387677D01*
X245041Y-388273D01*
X245636Y-388671D01*
X246339Y-388810D01*
X247041Y-388671D01*
X247476Y-388380D01*
X248059Y-388472D01*
X248112Y-388551D01*
X248707Y-388949D01*
X249410Y-389089D01*
X250112Y-388949D01*
X250707Y-388551D01*
X251105Y-387956D01*
X251245Y-387253D01*
X251105Y-386551D01*
X250707Y-385956D01*
X250112Y-385558D01*
X249410Y-385418D01*
X248707Y-385558D01*
X248327Y-385812D01*
X247689Y-385756D01*
X247636Y-385677D01*
X247041Y-385279D01*
X246339Y-385140D01*
D02*
G37*
G36*
X181534Y-385922D02*
X180832Y-386061D01*
X180236Y-386459D01*
X179838Y-387055D01*
X179699Y-387757D01*
X179838Y-388459D01*
X180236Y-389055D01*
X180832Y-389453D01*
X181534Y-389592D01*
X182236Y-389453D01*
X182832Y-389055D01*
X183229Y-388459D01*
X183369Y-387757D01*
X183229Y-387055D01*
X182832Y-386459D01*
X182236Y-386061D01*
X181534Y-385922D01*
D02*
G37*
G36*
X0Y-364854D02*
X-2118Y-365020D01*
X-4185Y-365516D01*
X-6148Y-366330D01*
X-7960Y-367440D01*
X-9575Y-368820D01*
X-10955Y-370436D01*
X-12066Y-372248D01*
X-12879Y-374211D01*
X-13375Y-376277D01*
X-13542Y-378395D01*
X-13375Y-380514D01*
X-12879Y-382580D01*
X-12066Y-384543D01*
X-10955Y-386355D01*
X-9575Y-387971D01*
X-7960Y-389351D01*
X-6148Y-390461D01*
X-4185Y-391274D01*
X-2118Y-391770D01*
X0Y-391937D01*
X2118Y-391770D01*
X4185Y-391274D01*
X6148Y-390461D01*
X7960Y-389351D01*
X9576Y-387971D01*
X10955Y-386355D01*
X12066Y-384543D01*
X12879Y-382580D01*
X13375Y-380514D01*
X13542Y-378395D01*
X13375Y-376277D01*
X12879Y-374211D01*
X12066Y-372248D01*
X10955Y-370436D01*
X9576Y-368820D01*
X7960Y-367440D01*
X6148Y-366330D01*
X4185Y-365516D01*
X2118Y-365020D01*
X0Y-364854D01*
D02*
G37*
%LPD*%
D211*
X574409Y7445D02*
D03*
D212*
Y-9055D02*
D03*
D217*
X321260Y-145669D02*
D03*
D236*
X298031Y-145512D02*
D03*
D240*
X608268Y-288779D02*
D03*
Y-271260D02*
D03*
D241*
X620079Y-263583D02*
D03*
Y-296457D02*
D03*
D242*
X354035Y-38976D02*
D03*
X424803D02*
D03*
X535827Y-112205D02*
D03*
D244*
X58268Y-243701D02*
D03*
X218110Y-323622D02*
D03*
D03*
X58268Y-243701D02*
D03*
D246*
X-18464Y-326781D02*
D03*
X1535D02*
D03*
Y-306781D02*
D03*
X-18464D02*
D03*
X-18465Y-273630D02*
D03*
X1535D02*
D03*
Y-253630D02*
D03*
X-18465D02*
D03*
Y-220480D02*
D03*
X1535D02*
D03*
Y-200480D02*
D03*
X-18465D02*
D03*
X-18464Y-167332D02*
D03*
X1535D02*
D03*
Y-147332D02*
D03*
X-18464D02*
D03*
D249*
X609449Y-138189D02*
D03*
X619449D02*
D03*
D250*
X593307Y-292126D02*
D03*
X599044Y-275032D02*
D03*
X585039Y-272835D02*
D03*
X581496D02*
D03*
X541093Y-284626D02*
D03*
X541411Y-269932D02*
D03*
X536489Y-269182D02*
D03*
X554724Y-272441D02*
D03*
X555460Y-284401D02*
D03*
X567525Y-286203D02*
D03*
X581890Y-290158D02*
D03*
X583815Y-275386D02*
D03*
X604724Y-274803D02*
D03*
X320761Y-183851D02*
D03*
X124016Y-110236D02*
D03*
X57422Y-128927D02*
D03*
X89312Y-128140D02*
D03*
X84981D02*
D03*
X80651D02*
D03*
X89312Y-123809D02*
D03*
X84981D02*
D03*
X80651D02*
D03*
X89312Y-119478D02*
D03*
X84981D02*
D03*
X80651D02*
D03*
X58407Y-137589D02*
D03*
X85044Y-139557D02*
D03*
X44134Y-115080D02*
D03*
X58210Y-108061D02*
D03*
X84981Y-108061D02*
D03*
X262724Y-107813D02*
D03*
X253082Y-110236D02*
D03*
X364567Y-326378D02*
D03*
X357575Y-327776D02*
D03*
X357480Y-332677D02*
D03*
X350787Y-329921D02*
D03*
X205906Y-372441D02*
D03*
X211024D02*
D03*
X222835Y-372047D02*
D03*
X217323Y-371654D02*
D03*
X237795D02*
D03*
X242897Y-371864D02*
D03*
X250394Y-375984D02*
D03*
X259449Y-373228D02*
D03*
X268504Y-372047D02*
D03*
X274803Y-372441D02*
D03*
X266929Y-385039D02*
D03*
X243701Y-389370D02*
D03*
X250394Y-384646D02*
D03*
X227953Y-383858D02*
D03*
X233858Y-384646D02*
D03*
X213386D02*
D03*
X24500Y-8429D02*
D03*
X603150Y-235946D02*
D03*
X604316Y-246600D02*
D03*
X152756Y-49606D02*
D03*
X149935Y-124206D02*
D03*
X464961Y-125197D02*
D03*
X50000Y-44094D02*
D03*
X383465Y-234252D02*
D03*
X389764D02*
D03*
X386614Y-237402D02*
D03*
Y-231102D02*
D03*
X26378Y-20472D02*
D03*
X24409Y-16535D02*
D03*
X26378Y-10630D02*
D03*
X230709Y-242913D02*
D03*
X476968Y-76378D02*
D03*
X135433Y-79134D02*
D03*
X428346Y-187795D02*
D03*
X140070Y-132385D02*
D03*
X182677Y-94488D02*
D03*
X189764Y-100787D02*
D03*
X196850Y-94488D02*
D03*
X149803Y-9238D02*
D03*
X150000Y-787D02*
D03*
X474409Y-265748D02*
D03*
X480315Y-259744D02*
D03*
Y-271752D02*
D03*
X478346Y-305118D02*
D03*
X477362Y-313767D02*
D03*
X624938Y-196373D02*
D03*
X624926Y-201353D02*
D03*
X624938Y-206373D02*
D03*
X624918Y-211353D02*
D03*
X625079Y-173898D02*
D03*
X624685Y-163898D02*
D03*
X118110Y-36220D02*
D03*
X117717Y-47293D02*
D03*
X578332Y-261235D02*
D03*
X507874Y-255906D02*
D03*
X534814Y-297190D02*
D03*
X528960Y-296841D02*
D03*
X495276Y-298130D02*
D03*
X503346Y-297967D02*
D03*
X501181Y-298130D02*
D03*
X516929D02*
D03*
X522835Y-297736D02*
D03*
X540945Y-297342D02*
D03*
X546457D02*
D03*
X562205Y-297736D02*
D03*
X568110D02*
D03*
X570472D02*
D03*
X576378D02*
D03*
X564173Y-255906D02*
D03*
X494882Y-262303D02*
D03*
X495669Y-255512D02*
D03*
X209449Y7087D02*
D03*
X203937Y1969D02*
D03*
X214173Y1181D02*
D03*
Y-79134D02*
D03*
X205118Y-79380D02*
D03*
X168504Y-79528D02*
D03*
Y-73622D02*
D03*
Y-71260D02*
D03*
Y-65354D02*
D03*
X168898Y-49606D02*
D03*
Y-44094D02*
D03*
X168504Y-37795D02*
D03*
Y-31890D02*
D03*
Y-25984D02*
D03*
X168110Y-20079D02*
D03*
Y-4331D02*
D03*
X168273Y-6496D02*
D03*
X168110Y1575D02*
D03*
X144095Y-80315D02*
D03*
X87795Y-99606D02*
D03*
X535827Y-345276D02*
D03*
X555512Y-340158D02*
D03*
X568898Y-319009D02*
D03*
X570079Y-309921D02*
D03*
X536221Y-300787D02*
D03*
X505512Y-303150D02*
D03*
X455118Y-92520D02*
D03*
X460236Y-87795D02*
D03*
Y-92520D02*
D03*
X454724Y-87795D02*
D03*
X624409Y-31496D02*
D03*
X620079Y-31890D02*
D03*
X615748Y-32283D02*
D03*
X611417Y-33071D02*
D03*
X620866Y-35827D02*
D03*
X611811Y-38189D02*
D03*
X542913Y-72835D02*
D03*
Y-69291D02*
D03*
Y-65748D02*
D03*
Y-61811D02*
D03*
Y-58268D02*
D03*
X595276Y-79921D02*
D03*
X608405Y-70079D02*
D03*
X238189Y-138976D02*
D03*
X217405Y-138189D02*
D03*
X214173Y-107087D02*
D03*
X192126Y-111811D02*
D03*
X133099Y-119984D02*
D03*
X148425Y-104336D02*
D03*
X153150Y-103412D02*
D03*
X158268Y-107480D02*
D03*
X168110Y-103937D02*
D03*
X161417Y-95276D02*
D03*
Y-107480D02*
D03*
X152398Y-117717D02*
D03*
X156926Y-111614D02*
D03*
X168343Y-110827D02*
D03*
X189209Y-131339D02*
D03*
Y-117480D02*
D03*
X173461Y-127362D02*
D03*
X165587Y-139961D02*
D03*
X151808Y-137205D02*
D03*
X106693Y15354D02*
D03*
X107087Y9449D02*
D03*
X111024D02*
D03*
Y15354D02*
D03*
X105512Y-79921D02*
D03*
X109843D02*
D03*
Y-74410D02*
D03*
X105512D02*
D03*
X99606Y-63779D02*
D03*
X107874D02*
D03*
Y-59842D02*
D03*
X99606D02*
D03*
X74616Y-61723D02*
D03*
X47441Y-5709D02*
D03*
Y-11811D02*
D03*
X75394Y-5709D02*
D03*
Y-11811D02*
D03*
X66142D02*
D03*
X61417D02*
D03*
X56693D02*
D03*
Y-16535D02*
D03*
X61417D02*
D03*
X66142D02*
D03*
Y-21260D02*
D03*
X61417D02*
D03*
X52362Y-35531D02*
D03*
X72795Y-53355D02*
D03*
X84252Y-9055D02*
D03*
Y-5906D02*
D03*
Y-2362D02*
D03*
X88257Y-2500D02*
D03*
X93608Y-3379D02*
D03*
X90158Y-7480D02*
D03*
X97408Y-10197D02*
D03*
X106693Y-27559D02*
D03*
X105282Y-19291D02*
D03*
X383083Y-128504D02*
D03*
X336221Y-122047D02*
D03*
X333465D02*
D03*
X330315Y-121653D02*
D03*
X335827Y-164173D02*
D03*
X333071D02*
D03*
X329919Y-164008D02*
D03*
X329656Y-142480D02*
D03*
X329722Y-145827D02*
D03*
X347638Y-119882D02*
D03*
X347244Y-113189D02*
D03*
X355035Y-105876D02*
D03*
X390654Y-104510D02*
D03*
X383465Y-103543D02*
D03*
X448425Y-165354D02*
D03*
X451968D02*
D03*
X455512D02*
D03*
X458661D02*
D03*
X442815Y-161747D02*
D03*
Y-165847D02*
D03*
X439561D02*
D03*
X425984Y-109843D02*
D03*
X425630Y-112894D02*
D03*
X416535Y-120768D02*
D03*
X423622Y-115354D02*
D03*
X436811Y-153543D02*
D03*
X418110D02*
D03*
X422835D02*
D03*
X427559D02*
D03*
Y-148819D02*
D03*
X418110D02*
D03*
X422835D02*
D03*
Y-144095D02*
D03*
X418110D02*
D03*
X406693Y-125984D02*
D03*
X408268Y-124409D02*
D03*
Y-122047D02*
D03*
X445276Y-103543D02*
D03*
X444488Y-106299D02*
D03*
X440945Y-105905D02*
D03*
X436221Y-106299D02*
D03*
X434347Y-103743D02*
D03*
X434646Y-100787D02*
D03*
X431496Y-100000D02*
D03*
X281890Y-200771D02*
D03*
X288583Y-195276D02*
D03*
X275503D02*
D03*
X356693Y-288583D02*
D03*
X355741Y-296063D02*
D03*
X314961Y-293701D02*
D03*
X320472Y-299569D02*
D03*
Y-287865D02*
D03*
X333465Y-292913D02*
D03*
X339370Y-286162D02*
D03*
Y-298819D02*
D03*
X325590Y-246324D02*
D03*
Y-232344D02*
D03*
X317009Y-239764D02*
D03*
X400000Y-219291D02*
D03*
X398472Y-235531D02*
D03*
X367654Y-236614D02*
D03*
X414772Y-353273D02*
D03*
X460900Y-354061D02*
D03*
X499302Y-353737D02*
D03*
X543718Y-353540D02*
D03*
X605512Y-261024D02*
D03*
Y-256693D02*
D03*
X622835Y-244094D02*
D03*
Y-235433D02*
D03*
X622101Y-250000D02*
D03*
X622803Y-241006D02*
D03*
X619148Y-302756D02*
D03*
X598583Y-353307D02*
D03*
X598898Y-313307D02*
D03*
X22047Y-335433D02*
D03*
X2097Y-349213D02*
D03*
X27067Y-282677D02*
D03*
X5584Y-238905D02*
D03*
X35120Y-228937D02*
D03*
X10630Y-197638D02*
D03*
X19976Y-200787D02*
D03*
Y-220472D02*
D03*
X22441Y-167323D02*
D03*
X19685D02*
D03*
X16929D02*
D03*
X23228Y-147244D02*
D03*
X20079D02*
D03*
X17323D02*
D03*
X27165Y-179134D02*
D03*
X-7874Y-188976D02*
D03*
X364173Y-332283D02*
D03*
X370079D02*
D03*
X377658Y-327985D02*
D03*
X369703Y-326432D02*
D03*
X344882Y-328346D02*
D03*
X348425Y-328740D02*
D03*
X381989Y-348458D02*
D03*
X376870D02*
D03*
X374902D02*
D03*
X370472Y-348425D02*
D03*
X368294Y-348913D02*
D03*
X363878Y-348458D02*
D03*
X361910D02*
D03*
X356792D02*
D03*
X349705Y-348064D02*
D03*
X354823Y-348851D02*
D03*
X156693Y-18110D02*
D03*
X203689Y-248906D02*
D03*
X203937Y-242913D02*
D03*
X451674Y-283940D02*
D03*
X381989Y-331971D02*
D03*
X370178Y-315042D02*
D03*
X342618Y-315081D02*
D03*
X451674Y-234727D02*
D03*
X258702Y-264859D02*
D03*
X445768Y-254381D02*
D03*
X359874Y-183841D02*
D03*
X263322Y-246466D02*
D03*
X340847Y-179215D02*
D03*
X451674Y-244570D02*
D03*
X258760Y-256529D02*
D03*
X445768Y-264255D02*
D03*
X350327Y-183546D02*
D03*
X263622Y-236666D02*
D03*
X352461Y-315042D02*
D03*
X330705Y-179215D02*
D03*
X263122Y-285766D02*
D03*
X364272Y-315042D02*
D03*
X343012Y-332365D02*
D03*
X451674Y-254381D02*
D03*
X350327Y-179215D02*
D03*
X258622Y-246466D02*
D03*
X322933Y-332365D02*
D03*
X445768Y-275261D02*
D03*
X340256Y-183841D02*
D03*
X263580Y-226943D02*
D03*
X445768Y-224885D02*
D03*
X320473Y-179117D02*
D03*
X263322Y-276066D02*
D03*
X352106Y-332482D02*
D03*
X451674Y-264255D02*
D03*
X259022Y-236566D02*
D03*
X322540Y-315042D02*
D03*
X445768Y-283940D02*
D03*
X331091Y-184050D02*
D03*
X258622Y-285766D02*
D03*
X376477Y-315042D02*
D03*
X357973Y-315042D02*
D03*
X445768Y-234727D02*
D03*
X379496Y-183803D02*
D03*
Y-179215D02*
D03*
X262922Y-265040D02*
D03*
X332776Y-332365D02*
D03*
X451674Y-275261D02*
D03*
X369981Y-179215D02*
D03*
X258922Y-226766D02*
D03*
X451674Y-224885D02*
D03*
X360138Y-179215D02*
D03*
X258622Y-276066D02*
D03*
X381595Y-315042D02*
D03*
X445768Y-244570D02*
D03*
X369685Y-183841D02*
D03*
X263681Y-256529D02*
D03*
X332382Y-315042D02*
D03*
X19976Y-252953D02*
D03*
Y-272638D02*
D03*
Y-326772D02*
D03*
Y-307087D02*
D03*
X100729Y-123872D02*
D03*
X163071Y-390730D02*
D03*
X259285Y-390247D02*
D03*
X267204Y-390009D02*
D03*
X216162Y-390947D02*
D03*
X235144Y-390416D02*
D03*
X251456Y-390009D02*
D03*
X226063Y-390722D02*
D03*
X281201Y-390009D02*
D03*
X174941Y-390600D02*
D03*
X202441D02*
D03*
M02*
